FILE_TYPE = MACRO_DRAWING;
SET COLOR_WIRE YELLOW;
SET COLOR_PROP ORANGE;
SET COLOR_DOT WHITE;
SET COLOR_ARC YELLOW;
SET COLOR_BODY GREEN;
SET COLOR_NOTE PURPLE;
SET PROP_DISPLAY VALUE;
SET PAGE_NUMBER P32;
SET PATH_NUMBER P145;
FORCEADD OFFPAGE..2
(1000 125);
FORCEPROP 2 LAST $XR0 10 
J 0
(1189 125);
DISPLAY 0.638298 (1189 125);
PAINT MONO (1189 125);
FORCEPROP 2 LAST $XR1 32 
J 0
(1279 125);
DISPLAY 0.638298 (1279 125);
PAINT MONO (1279 125);
FORCEPROP 2 LAST CDS_LIB standard
J 0
(1000 125);
DISPLAY INVISIBLE (1000 125);
FORCEPROP 1 LAST OFFPAGE TRUE
J 0
(1325 0);
DISPLAY 0.872340 (1325 0);
PAINT GREEN (1325 0);
DISPLAY INVISIBLE (1325 0);
FORCEPROP 1 LAST COMMENT_BODY TRUE
J 0
(955 30);
DISPLAY 0.872340 (955 30);
PAINT PEACH (955 30);
DISPLAY INVISIBLE (955 30);
FORCEPROP 2 LAST PATH I100
J 0
(1250 175);
DISPLAY 1.021277 (1250 175);
DISPLAY INVISIBLE (1250 175);
FORCEADD OFFPAGE..2
(1000 -225);
FORCEPROP 2 LAST $XR0 32 
J 0
(1189 -225);
DISPLAY 0.638298 (1189 -225);
PAINT MONO (1189 -225);
FORCEPROP 2 LAST CDS_LIB standard
J 0
(1000 -225);
DISPLAY INVISIBLE (1000 -225);
FORCEPROP 1 LAST OFFPAGE TRUE
J 0
(1325 -350);
DISPLAY 0.872340 (1325 -350);
PAINT GREEN (1325 -350);
DISPLAY INVISIBLE (1325 -350);
FORCEPROP 1 LAST COMMENT_BODY TRUE
J 0
(955 -320);
DISPLAY 0.872340 (955 -320);
PAINT PEACH (955 -320);
DISPLAY INVISIBLE (955 -320);
FORCEPROP 2 LAST PATH I101
J 0
(1300 -175);
DISPLAY 1.021277 (1300 -175);
DISPLAY INVISIBLE (1300 -175);
FORCEADD OFFPAGE..2
(1000 -350);
FORCEPROP 2 LAST $XR0 32 
J 0
(1189 -350);
DISPLAY 0.638298 (1189 -350);
PAINT MONO (1189 -350);
FORCEPROP 2 LAST $XR1 10 
J 0
(1279 -350);
DISPLAY 0.638298 (1279 -350);
PAINT MONO (1279 -350);
FORCEPROP 2 LAST CDS_LIB standard
J 0
(1000 -350);
DISPLAY INVISIBLE (1000 -350);
FORCEPROP 1 LAST OFFPAGE TRUE
J 0
(1325 -475);
DISPLAY 0.872340 (1325 -475);
PAINT GREEN (1325 -475);
DISPLAY INVISIBLE (1325 -475);
FORCEPROP 1 LAST COMMENT_BODY TRUE
J 0
(955 -445);
DISPLAY 0.872340 (955 -445);
PAINT PEACH (955 -445);
DISPLAY INVISIBLE (955 -445);
FORCEPROP 2 LAST PATH I102
J 0
(1300 -300);
DISPLAY 1.021277 (1300 -300);
DISPLAY INVISIBLE (1300 -300);
FORCEADD Q_RES..1
(-200 450);
FORCEPROP 1 LAST MATERIAL CHIP
J 0
(100 450);
DISPLAY 0.510638 (100 450);
PAINT SKYBLUE (100 450);
FORCEPROP 1 LAST VALUE 10K
J 2
(50 450);
DISPLAY 0.510638 (50 450);
PAINT SKYBLUE (50 450);
FORCEPROP 2 LAST CDS_LIB pure_quanta
J 0
(-200 450);
DISPLAY INVISIBLE (-200 450);
FORCEPROP 1 LAST TOLERANCE 1%
J 0
(-200 350);
DISPLAY 0.510638 (-200 350);
PAINT SKYBLUE (-200 350);
DISPLAY INVISIBLE (-200 350);
FORCEPROP 1 LAST PATH I103
J 0
(-250 600);
DISPLAY 0.978723 (-250 600);
PAINT WHITE (-250 600);
DISPLAY INVISIBLE (-250 600);
FORCEPROP 1 LAST WATTAGE 1/16W
J 2
(-225 300);
DISPLAY 0.510638 (-225 300);
PAINT SKYBLUE (-225 300);
DISPLAY INVISIBLE (-225 300);
FORCEPROP 1 LAST PACK_TYPE 0402LF
J 0
(50 300);
DISPLAY 0.510638 (50 300);
PAINT SKYBLUE (50 300);
DISPLAY INVISIBLE (50 300);
FORCEPROP 1 LAST PART_NUMBER CS31002FB08
J 0
(-250 550);
DISPLAY 0.510638 (-250 550);
PAINT WHITE (-250 550);
DISPLAY INVISIBLE (-250 550);
FORCEPROP 1 LAST LOCATION R226
J 0
(-500 450);
DISPLAY 0.702128 (-500 450);
PAINT YELLOW (-500 450);
FORCEPROP 1 LASTPIN (-300 450) $PN 1
J 0
(-288 462);
DISPLAY 0.808511 (-288 462);
PAINT WHITE (-288 462);
FORCEPROP 1 LASTPIN (-100 450) $PN 2
J 0
(-138 462);
DISPLAY 0.808511 (-138 462);
PAINT WHITE (-138 462);
FORCEPROP 0 LAST $SEC 1
J 0
(125 500);
DISPLAY 0.680851 (125 500);
PAINT MONO (125 500);
DISPLAY INVISIBLE (125 500);
FORCEPROP 0 LAST CDS_SEC 1
J 0
(125 500);
DISPLAY 0.680851 (125 500);
DISPLAY INVISIBLE (125 500);
FORCEADD Q_RES..1
(-200 250);
FORCEPROP 1 LAST VALUE 10K
J 2
(50 250);
DISPLAY 0.510638 (50 250);
PAINT SKYBLUE (50 250);
FORCEPROP 1 LAST MATERIAL CHIP
J 0
(100 250);
DISPLAY 0.510638 (100 250);
PAINT SKYBLUE (100 250);
FORCEPROP 2 LAST CDS_LIB pure_quanta
J 0
(-200 250);
DISPLAY INVISIBLE (-200 250);
FORCEPROP 1 LAST TOLERANCE 1%
J 0
(-200 150);
DISPLAY 0.510638 (-200 150);
PAINT SKYBLUE (-200 150);
DISPLAY INVISIBLE (-200 150);
FORCEPROP 1 LAST PATH I104
J 0
(-250 400);
DISPLAY 0.978723 (-250 400);
PAINT WHITE (-250 400);
DISPLAY INVISIBLE (-250 400);
FORCEPROP 1 LAST WATTAGE 1/16W
J 2
(-225 100);
DISPLAY 0.510638 (-225 100);
PAINT SKYBLUE (-225 100);
DISPLAY INVISIBLE (-225 100);
FORCEPROP 1 LAST PACK_TYPE 0402LF
J 0
(50 100);
DISPLAY 0.510638 (50 100);
PAINT SKYBLUE (50 100);
DISPLAY INVISIBLE (50 100);
FORCEPROP 1 LAST PART_NUMBER CS31002FB08
J 0
(-250 350);
DISPLAY 0.510638 (-250 350);
PAINT WHITE (-250 350);
DISPLAY INVISIBLE (-250 350);
FORCEPROP 1 LAST LOCATION R227
J 0
(-500 250);
DISPLAY 0.702128 (-500 250);
PAINT YELLOW (-500 250);
FORCEPROP 1 LASTPIN (-300 250) $PN 1
J 0
(-288 262);
DISPLAY 0.808511 (-288 262);
PAINT WHITE (-288 262);
FORCEPROP 1 LASTPIN (-100 250) $PN 2
J 0
(-138 262);
DISPLAY 0.808511 (-138 262);
PAINT WHITE (-138 262);
FORCEPROP 0 LAST $SEC 1
J 0
(125 300);
DISPLAY 0.680851 (125 300);
PAINT MONO (125 300);
DISPLAY INVISIBLE (125 300);
FORCEPROP 0 LAST CDS_SEC 1
J 0
(125 300);
DISPLAY 0.680851 (125 300);
DISPLAY INVISIBLE (125 300);
FORCEADD Q_RES..1
(-200 125);
FORCEPROP 1 LAST MATERIAL CHIP
J 0
(100 125);
DISPLAY 0.510638 (100 125);
PAINT SKYBLUE (100 125);
FORCEPROP 1 LAST VALUE 10K
J 2
(50 125);
DISPLAY 0.510638 (50 125);
PAINT SKYBLUE (50 125);
FORCEPROP 2 LAST CDS_LIB pure_quanta
J 0
(-200 125);
DISPLAY INVISIBLE (-200 125);
FORCEPROP 1 LAST TOLERANCE 1%
J 0
(-200 25);
DISPLAY 0.510638 (-200 25);
PAINT SKYBLUE (-200 25);
DISPLAY INVISIBLE (-200 25);
FORCEPROP 1 LAST PATH I105
J 0
(-250 275);
DISPLAY 0.978723 (-250 275);
PAINT WHITE (-250 275);
DISPLAY INVISIBLE (-250 275);
FORCEPROP 1 LAST WATTAGE 1/16W
J 2
(-225 -25);
DISPLAY 0.510638 (-225 -25);
PAINT SKYBLUE (-225 -25);
DISPLAY INVISIBLE (-225 -25);
FORCEPROP 1 LAST PACK_TYPE 0402LF
J 0
(50 -25);
DISPLAY 0.510638 (50 -25);
PAINT SKYBLUE (50 -25);
DISPLAY INVISIBLE (50 -25);
FORCEPROP 1 LAST PART_NUMBER CS31002FB08
J 0
(-250 225);
DISPLAY 0.510638 (-250 225);
PAINT WHITE (-250 225);
DISPLAY INVISIBLE (-250 225);
FORCEPROP 1 LAST LOCATION R230
J 0
(-500 125);
DISPLAY 0.702128 (-500 125);
PAINT YELLOW (-500 125);
FORCEPROP 1 LASTPIN (-300 125) $PN 1
J 0
(-288 137);
DISPLAY 0.808511 (-288 137);
PAINT WHITE (-288 137);
FORCEPROP 1 LASTPIN (-100 125) $PN 2
J 0
(-138 137);
DISPLAY 0.808511 (-138 137);
PAINT WHITE (-138 137);
FORCEPROP 0 LAST $SEC 1
J 0
(125 175);
DISPLAY 0.680851 (125 175);
PAINT MONO (125 175);
DISPLAY INVISIBLE (125 175);
FORCEPROP 0 LAST CDS_SEC 1
J 0
(125 175);
DISPLAY 0.680851 (125 175);
DISPLAY INVISIBLE (125 175);
FORCEADD Q_RES..1
(-200 -225);
FORCEPROP 1 LAST MATERIAL EMPTY
J 0
(100 -225);
DISPLAY 0.510638 (100 -225);
PAINT RED (100 -225);
FORCEPROP 1 LAST VALUE 4.7K
J 2
(50 -225);
DISPLAY 0.510638 (50 -225);
PAINT SKYBLUE (50 -225);
FORCEPROP 2 LAST CDS_LIB pure_quanta
J 0
(-200 -225);
DISPLAY INVISIBLE (-200 -225);
FORCEPROP 1 LAST PATH I106
J 0
(-250 -75);
DISPLAY 0.978723 (-250 -75);
PAINT WHITE (-250 -75);
DISPLAY INVISIBLE (-250 -75);
FORCEPROP 1 LAST PART_NUMBER CS24702FB06
J 0
(-250 -125);
DISPLAY 0.510638 (-250 -125);
PAINT WHITE (-250 -125);
DISPLAY INVISIBLE (-250 -125);
FORCEPROP 1 LAST PACK_TYPE 0402LF
J 0
(50 -375);
DISPLAY 0.510638 (50 -375);
PAINT SKYBLUE (50 -375);
DISPLAY INVISIBLE (50 -375);
FORCEPROP 1 LAST WATTAGE 1/16W
J 2
(-225 -375);
DISPLAY 0.510638 (-225 -375);
PAINT SKYBLUE (-225 -375);
DISPLAY INVISIBLE (-225 -375);
FORCEPROP 1 LAST TOLERANCE 1%
J 0
(-200 -325);
DISPLAY 0.510638 (-200 -325);
PAINT SKYBLUE (-200 -325);
DISPLAY INVISIBLE (-200 -325);
FORCEPROP 1 LAST LOCATION R229
J 0
(-500 -225);
DISPLAY 0.702128 (-500 -225);
PAINT YELLOW (-500 -225);
FORCEPROP 1 LASTPIN (-300 -225) $PN 1
J 0
(-288 -213);
DISPLAY 0.808511 (-288 -213);
PAINT WHITE (-288 -213);
FORCEPROP 1 LASTPIN (-100 -225) $PN 2
J 0
(-138 -213);
DISPLAY 0.808511 (-138 -213);
PAINT WHITE (-138 -213);
FORCEPROP 0 LAST $SEC 1
J 0
(125 -175);
DISPLAY 0.680851 (125 -175);
PAINT MONO (125 -175);
DISPLAY INVISIBLE (125 -175);
FORCEPROP 0 LAST CDS_SEC 1
J 0
(125 -175);
DISPLAY 0.680851 (125 -175);
DISPLAY INVISIBLE (125 -175);
FORCEADD Q_RES..1
(-200 -350);
FORCEPROP 1 LAST VALUE 10K
J 2
(50 -350);
DISPLAY 0.510638 (50 -350);
PAINT SKYBLUE (50 -350);
FORCEPROP 1 LAST MATERIAL EMPTY
J 0
(100 -350);
DISPLAY 0.510638 (100 -350);
PAINT RED (100 -350);
FORCEPROP 2 LAST CDS_LIB pure_quanta
J 0
(-200 -350);
DISPLAY INVISIBLE (-200 -350);
FORCEPROP 1 LAST PATH I107
J 0
(-250 -200);
DISPLAY 0.978723 (-250 -200);
PAINT WHITE (-250 -200);
DISPLAY INVISIBLE (-250 -200);
FORCEPROP 1 LAST WATTAGE 1/16W
J 2
(-225 -500);
DISPLAY 0.510638 (-225 -500);
PAINT SKYBLUE (-225 -500);
DISPLAY INVISIBLE (-225 -500);
FORCEPROP 1 LAST TOLERANCE 1%
J 0
(-200 -450);
DISPLAY 0.510638 (-200 -450);
PAINT SKYBLUE (-200 -450);
DISPLAY INVISIBLE (-200 -450);
FORCEPROP 1 LAST PACK_TYPE 0402LF
J 0
(50 -500);
DISPLAY 0.510638 (50 -500);
PAINT SKYBLUE (50 -500);
DISPLAY INVISIBLE (50 -500);
FORCEPROP 1 LAST PART_NUMBER CS31002FB08
J 0
(-250 -250);
DISPLAY 0.510638 (-250 -250);
PAINT WHITE (-250 -250);
DISPLAY INVISIBLE (-250 -250);
FORCEPROP 1 LAST LOCATION R228
J 0
(-500 -350);
DISPLAY 0.702128 (-500 -350);
PAINT YELLOW (-500 -350);
FORCEPROP 1 LASTPIN (-300 -350) $PN 1
J 0
(-288 -338);
DISPLAY 0.808511 (-288 -338);
PAINT WHITE (-288 -338);
FORCEPROP 1 LASTPIN (-100 -350) $PN 2
J 0
(-138 -338);
DISPLAY 0.808511 (-138 -338);
PAINT WHITE (-138 -338);
FORCEPROP 0 LAST $SEC 1
J 0
(125 -300);
DISPLAY 0.680851 (125 -300);
PAINT MONO (125 -300);
DISPLAY INVISIBLE (125 -300);
FORCEPROP 0 LAST CDS_SEC 1
J 0
(125 -300);
DISPLAY 0.680851 (125 -300);
DISPLAY INVISIBLE (125 -300);
FORCEADD UNIVERSAL_POWER..1
(-650 725);
FORCEPROP 3 LASTPIN (-650 675) SIG_NAME P3V3_AUX\g
J 0
(-640 685);
DISPLAY 0.659574 (-640 685);
PAINT MONO (-640 685);
DISPLAY INVISIBLE (-640 685);
FORCEPROP 1 LAST HDL_POWER P3V3_AUX
J 1
(-650 775);
DISPLAY 0.702128 (-650 775);
PAINT GREEN (-650 775);
FORCEPROP 2 LAST CDS_LIB logical_power
J 0
(-650 725);
DISPLAY INVISIBLE (-650 725);
FORCEPROP 1 LAST PATH I108
J 0
(-600 750);
DISPLAY 0.872340 (-600 750);
PAINT AQUA (-600 750);
DISPLAY INVISIBLE (-600 750);
FORCEADD OFFPAGE..2
(-1325 425);
FORCEPROP 2 LAST $XR0 15 
J 0
(-1136 425);
DISPLAY 0.638298 (-1136 425);
PAINT MONO (-1136 425);
FORCEPROP 2 LAST $XR1 32 
J 0
(-1046 425);
DISPLAY 0.638298 (-1046 425);
PAINT MONO (-1046 425);
FORCEPROP 2 LAST CDS_LIB standard
J 0
(-1325 425);
DISPLAY INVISIBLE (-1325 425);
FORCEPROP 1 LAST OFFPAGE TRUE
J 0
(-1000 300);
DISPLAY 0.872340 (-1000 300);
PAINT GREEN (-1000 300);
DISPLAY INVISIBLE (-1000 300);
FORCEPROP 1 LAST COMMENT_BODY TRUE
J 0
(-1370 330);
DISPLAY 0.872340 (-1370 330);
PAINT PEACH (-1370 330);
DISPLAY INVISIBLE (-1370 330);
FORCEPROP 2 LAST PATH I109
J 0
(-1025 475);
DISPLAY 1.021277 (-1025 475);
DISPLAY INVISIBLE (-1025 475);
FORCEADD OFFPAGE..4
(-1325 -200);
FORCEPROP 2 LAST $XR0 15 
J 0
(-1139 -200);
DISPLAY 0.638298 (-1139 -200);
PAINT MONO (-1139 -200);
FORCEPROP 2 LAST CDS_LIB standard
J 0
(-1325 -200);
DISPLAY INVISIBLE (-1325 -200);
FORCEPROP 1 LAST OFFPAGE TRUE
J 0
(-1000 -325);
DISPLAY 1.574468 (-1000 -325);
PAINT GREEN (-1000 -325);
DISPLAY INVISIBLE (-1000 -325);
FORCEPROP 1 LAST COMMENT_BODY TRUE
J 0
(-1350 -300);
DISPLAY 1.574468 (-1350 -300);
PAINT PEACH (-1350 -300);
DISPLAY INVISIBLE (-1350 -300);
FORCEPROP 2 LAST PATH I110
J 0
(-1125 -150);
DISPLAY 1.021277 (-1125 -150);
DISPLAY INVISIBLE (-1125 -150);
FORCEADD OFFPAGE..2
(-1325 275);
FORCEPROP 2 LAST $XR1 15 
J 0
(-1046 275);
DISPLAY 0.638298 (-1046 275);
PAINT MONO (-1046 275);
FORCEPROP 2 LAST $XR0 32 
J 0
(-1136 275);
DISPLAY 0.638298 (-1136 275);
PAINT MONO (-1136 275);
FORCEPROP 2 LAST CDS_LIB standard
J 0
(-1325 275);
DISPLAY INVISIBLE (-1325 275);
FORCEPROP 1 LAST OFFPAGE TRUE
J 0
(-1000 150);
DISPLAY 0.872340 (-1000 150);
PAINT GREEN (-1000 150);
DISPLAY INVISIBLE (-1000 150);
FORCEPROP 1 LAST COMMENT_BODY TRUE
J 0
(-1370 180);
DISPLAY 0.872340 (-1370 180);
PAINT PEACH (-1370 180);
DISPLAY INVISIBLE (-1370 180);
FORCEPROP 2 LAST PATH I111
J 0
(-1025 325);
DISPLAY 1.021277 (-1025 325);
DISPLAY INVISIBLE (-1025 325);
FORCEADD OFFPAGE..2
(-1325 350);
FORCEPROP 2 LAST $XR1 32 
J 0
(-1046 350);
DISPLAY 0.638298 (-1046 350);
PAINT MONO (-1046 350);
FORCEPROP 2 LAST $XR0 15 
J 0
(-1136 350);
DISPLAY 0.638298 (-1136 350);
PAINT MONO (-1136 350);
FORCEPROP 2 LAST CDS_LIB standard
J 0
(-1325 350);
DISPLAY INVISIBLE (-1325 350);
FORCEPROP 1 LAST OFFPAGE TRUE
J 0
(-1000 225);
DISPLAY 0.872340 (-1000 225);
PAINT GREEN (-1000 225);
DISPLAY INVISIBLE (-1000 225);
FORCEPROP 1 LAST COMMENT_BODY TRUE
J 0
(-1370 255);
DISPLAY 0.872340 (-1370 255);
PAINT PEACH (-1370 255);
DISPLAY INVISIBLE (-1370 255);
FORCEPROP 2 LAST PATH I112
J 0
(-1025 400);
DISPLAY 1.021277 (-1025 400);
DISPLAY INVISIBLE (-1025 400);
FORCEADD UNIVERSAL_GND..1
(-650 -675);
FORCEPROP 3 LASTPIN (-650 -625) SIG_NAME GND\g
J 0
(-640 -615);
DISPLAY 0.659574 (-640 -615);
PAINT MONO (-640 -615);
DISPLAY INVISIBLE (-640 -615);
FORCEPROP 2 LAST CDS_LIB logical_power
J 0
(-650 -675);
DISPLAY INVISIBLE (-650 -675);
FORCEPROP 1 LAST PATH I113
J 0
(-575 -675);
DISPLAY 0.872340 (-575 -675);
PAINT AQUA (-575 -675);
DISPLAY INVISIBLE (-575 -675);
FORCEPROP 1 LAST HDL_POWER GND
J 1
(-625 -750);
DISPLAY 0.702128 (-625 -750);
PAINT GREEN (-625 -750);
DISPLAY INVISIBLE (-625 -750);
FORCEADD Q_RES..1
(-2425 425);
FORCEPROP 1 LAST VALUE 10K
J 2
(-2175 425);
DISPLAY 0.510638 (-2175 425);
PAINT SKYBLUE (-2175 425);
FORCEPROP 1 LAST MATERIAL CHIP
J 0
(-2150 425);
DISPLAY 0.510638 (-2150 425);
PAINT SKYBLUE (-2150 425);
FORCEPROP 2 LAST CDS_LIB pure_quanta
J 0
(-2425 425);
DISPLAY INVISIBLE (-2425 425);
FORCEPROP 1 LAST TOLERANCE 1%
J 0
(-2425 325);
DISPLAY 0.510638 (-2425 325);
PAINT SKYBLUE (-2425 325);
DISPLAY INVISIBLE (-2425 325);
FORCEPROP 1 LAST PATH I117
J 0
(-2475 575);
DISPLAY 0.978723 (-2475 575);
PAINT WHITE (-2475 575);
DISPLAY INVISIBLE (-2475 575);
FORCEPROP 1 LAST WATTAGE 1/16W
J 2
(-2450 275);
DISPLAY 0.510638 (-2450 275);
PAINT SKYBLUE (-2450 275);
DISPLAY INVISIBLE (-2450 275);
FORCEPROP 1 LAST PACK_TYPE 0402LF
J 0
(-2175 275);
DISPLAY 0.510638 (-2175 275);
PAINT SKYBLUE (-2175 275);
DISPLAY INVISIBLE (-2175 275);
FORCEPROP 1 LAST PART_NUMBER CS31002FB08
J 0
(-2475 525);
DISPLAY 0.510638 (-2475 525);
PAINT WHITE (-2475 525);
DISPLAY INVISIBLE (-2475 525);
FORCEPROP 1 LAST LOCATION R203
J 0
(-2725 425);
DISPLAY 0.702128 (-2725 425);
PAINT YELLOW (-2725 425);
FORCEPROP 1 LASTPIN (-2525 425) $PN 1
J 0
(-2513 437);
DISPLAY 0.808511 (-2513 437);
PAINT WHITE (-2513 437);
FORCEPROP 1 LASTPIN (-2325 425) $PN 2
J 0
(-2363 437);
DISPLAY 0.808511 (-2363 437);
PAINT WHITE (-2363 437);
FORCEPROP 0 LAST $SEC 1
J 0
(-2100 475);
DISPLAY 0.680851 (-2100 475);
PAINT MONO (-2100 475);
DISPLAY INVISIBLE (-2100 475);
FORCEPROP 0 LAST CDS_SEC 1
J 0
(-2100 475);
DISPLAY 0.680851 (-2100 475);
DISPLAY INVISIBLE (-2100 475);
FORCEADD UNIVERSAL_POWER..1
(-2800 575);
FORCEPROP 3 LASTPIN (-2800 525) SIG_NAME P3V3_RGM\g
J 0
(-2790 535);
DISPLAY 0.659574 (-2790 535);
PAINT MONO (-2790 535);
DISPLAY INVISIBLE (-2790 535);
FORCEPROP 1 LAST HDL_POWER P3V3_RGM
J 1
(-2800 625);
DISPLAY 0.702128 (-2800 625);
PAINT GREEN (-2800 625);
FORCEPROP 2 LAST CDS_LIB logical_power
J 0
(-2800 575);
DISPLAY INVISIBLE (-2800 575);
FORCEPROP 1 LAST PATH I118
J 0
(-2750 600);
DISPLAY 0.872340 (-2750 600);
PAINT AQUA (-2750 600);
DISPLAY INVISIBLE (-2750 600);
FORCEADD Q_RES..1
(-2425 275);
FORCEPROP 1 LAST MATERIAL CHIP
J 0
(-2150 275);
DISPLAY 0.510638 (-2150 275);
PAINT SKYBLUE (-2150 275);
FORCEPROP 1 LAST VALUE 10K
J 2
(-2175 275);
DISPLAY 0.510638 (-2175 275);
PAINT SKYBLUE (-2175 275);
FORCEPROP 2 LAST CDS_LIB pure_quanta
J 0
(-2425 275);
DISPLAY INVISIBLE (-2425 275);
FORCEPROP 1 LAST PATH I119
J 0
(-2475 425);
DISPLAY 0.978723 (-2475 425);
PAINT WHITE (-2475 425);
DISPLAY INVISIBLE (-2475 425);
FORCEPROP 1 LAST PART_NUMBER CS31002FB08
J 0
(-2475 375);
DISPLAY 0.510638 (-2475 375);
PAINT WHITE (-2475 375);
DISPLAY INVISIBLE (-2475 375);
FORCEPROP 1 LAST PACK_TYPE 0402LF
J 0
(-2175 125);
DISPLAY 0.510638 (-2175 125);
PAINT SKYBLUE (-2175 125);
DISPLAY INVISIBLE (-2175 125);
FORCEPROP 1 LAST WATTAGE 1/16W
J 2
(-2450 125);
DISPLAY 0.510638 (-2450 125);
PAINT SKYBLUE (-2450 125);
DISPLAY INVISIBLE (-2450 125);
FORCEPROP 1 LAST TOLERANCE 1%
J 0
(-2425 175);
DISPLAY 0.510638 (-2425 175);
PAINT SKYBLUE (-2425 175);
DISPLAY INVISIBLE (-2425 175);
FORCEPROP 1 LAST LOCATION R523
J 0
(-2725 275);
DISPLAY 0.702128 (-2725 275);
PAINT YELLOW (-2725 275);
FORCEPROP 1 LASTPIN (-2525 275) $PN 1
J 0
(-2513 287);
DISPLAY 0.808511 (-2513 287);
PAINT WHITE (-2513 287);
FORCEPROP 1 LASTPIN (-2325 275) $PN 2
J 0
(-2363 287);
DISPLAY 0.808511 (-2363 287);
PAINT WHITE (-2363 287);
FORCEPROP 0 LAST $SEC 1
J 0
(-2100 325);
DISPLAY 0.680851 (-2100 325);
PAINT MONO (-2100 325);
DISPLAY INVISIBLE (-2100 325);
FORCEPROP 0 LAST CDS_SEC 1
J 0
(-2100 325);
DISPLAY 0.680851 (-2100 325);
DISPLAY INVISIBLE (-2100 325);
FORCEADD Q_RES..1
(-2425 350);
FORCEPROP 1 LAST MATERIAL CHIP
J 0
(-2150 350);
DISPLAY 0.510638 (-2150 350);
PAINT SKYBLUE (-2150 350);
FORCEPROP 1 LAST VALUE 10K
J 2
(-2175 350);
DISPLAY 0.510638 (-2175 350);
PAINT SKYBLUE (-2175 350);
FORCEPROP 2 LAST CDS_LIB pure_quanta
J 0
(-2425 350);
DISPLAY INVISIBLE (-2425 350);
FORCEPROP 1 LAST TOLERANCE 1%
J 0
(-2425 250);
DISPLAY 0.510638 (-2425 250);
PAINT SKYBLUE (-2425 250);
DISPLAY INVISIBLE (-2425 250);
FORCEPROP 1 LAST PATH I120
J 0
(-2475 500);
DISPLAY 0.978723 (-2475 500);
PAINT WHITE (-2475 500);
DISPLAY INVISIBLE (-2475 500);
FORCEPROP 1 LAST WATTAGE 1/16W
J 2
(-2450 200);
DISPLAY 0.510638 (-2450 200);
PAINT SKYBLUE (-2450 200);
DISPLAY INVISIBLE (-2450 200);
FORCEPROP 1 LAST PACK_TYPE 0402LF
J 0
(-2175 200);
DISPLAY 0.510638 (-2175 200);
PAINT SKYBLUE (-2175 200);
DISPLAY INVISIBLE (-2175 200);
FORCEPROP 1 LAST PART_NUMBER CS31002FB08
J 0
(-2475 450);
DISPLAY 0.510638 (-2475 450);
PAINT WHITE (-2475 450);
DISPLAY INVISIBLE (-2475 450);
FORCEPROP 1 LAST LOCATION R204
J 0
(-2725 350);
DISPLAY 0.702128 (-2725 350);
PAINT YELLOW (-2725 350);
FORCEPROP 1 LASTPIN (-2525 350) $PN 1
J 0
(-2513 362);
DISPLAY 0.808511 (-2513 362);
PAINT WHITE (-2513 362);
FORCEPROP 1 LASTPIN (-2325 350) $PN 2
J 0
(-2363 362);
DISPLAY 0.808511 (-2363 362);
PAINT WHITE (-2363 362);
FORCEPROP 0 LAST $SEC 1
J 0
(-2100 400);
DISPLAY 0.680851 (-2100 400);
PAINT MONO (-2100 400);
DISPLAY INVISIBLE (-2100 400);
FORCEPROP 0 LAST CDS_SEC 1
J 0
(-2100 400);
DISPLAY 0.680851 (-2100 400);
DISPLAY INVISIBLE (-2100 400);
FORCEADD UNIVERSAL_GND..1
(-2800 -650);
FORCEPROP 3 LASTPIN (-2800 -600) SIG_NAME GND\g
J 0
(-2790 -590);
DISPLAY 0.659574 (-2790 -590);
PAINT MONO (-2790 -590);
DISPLAY INVISIBLE (-2790 -590);
FORCEPROP 2 LAST CDS_LIB logical_power
J 0
(-2800 -650);
DISPLAY INVISIBLE (-2800 -650);
FORCEPROP 1 LAST HDL_POWER GND
J 1
(-2775 -725);
DISPLAY 0.702128 (-2775 -725);
PAINT GREEN (-2775 -725);
DISPLAY INVISIBLE (-2775 -725);
FORCEPROP 1 LAST PATH I123
J 0
(-2725 -650);
DISPLAY 0.872340 (-2725 -650);
PAINT AQUA (-2725 -650);
DISPLAY INVISIBLE (-2725 -650);
FORCEADD OFFPAGE..2
(-1325 -100);
FORCEPROP 2 LAST $XR0 15 
J 0
(-1136 -100);
DISPLAY 0.638298 (-1136 -100);
PAINT MONO (-1136 -100);
FORCEPROP 2 LAST $XR1 32 
J 0
(-1046 -100);
DISPLAY 0.638298 (-1046 -100);
PAINT MONO (-1046 -100);
FORCEPROP 2 LAST CDS_LIB standard
J 0
(-1325 -100);
DISPLAY INVISIBLE (-1325 -100);
FORCEPROP 1 LAST OFFPAGE TRUE
J 0
(-1000 -225);
DISPLAY 0.872340 (-1000 -225);
PAINT GREEN (-1000 -225);
DISPLAY INVISIBLE (-1000 -225);
FORCEPROP 1 LAST COMMENT_BODY TRUE
J 0
(-1370 -195);
DISPLAY 0.872340 (-1370 -195);
PAINT PEACH (-1370 -195);
DISPLAY INVISIBLE (-1370 -195);
FORCEPROP 2 LAST PATH I124
J 0
(-1025 -50);
DISPLAY 1.021277 (-1025 -50);
DISPLAY INVISIBLE (-1025 -50);
FORCEADD Q_RES..1
(-1525 3775);
FORCEPROP 1 LAST VALUE 33.2
J 0
(-1425 3775);
DISPLAY 0.510638 (-1425 3775);
PAINT SKYBLUE (-1425 3775);
FORCEPROP 1 LAST MATERIAL CHIP
J 0
(-1325 3775);
DISPLAY 0.510638 (-1325 3775);
PAINT SKYBLUE (-1325 3775);
FORCEPROP 1 LAST TOLERANCE 1%
J 0
(-1400 3775);
DISPLAY 0.510638 (-1400 3775);
PAINT SKYBLUE (-1400 3775);
DISPLAY INVISIBLE (-1400 3775);
FORCEPROP 1 LAST PART_NUMBER CS03322FB03
J 0
(-1575 3875);
DISPLAY 0.510638 (-1575 3875);
PAINT WHITE (-1575 3875);
DISPLAY INVISIBLE (-1575 3875);
FORCEPROP 1 LAST PACK_TYPE 0402LF
J 0
(-1275 3625);
DISPLAY 0.510638 (-1275 3625);
PAINT SKYBLUE (-1275 3625);
DISPLAY INVISIBLE (-1275 3625);
FORCEPROP 1 LAST WATTAGE 1/16W
J 2
(-1550 3625);
DISPLAY 0.510638 (-1550 3625);
PAINT SKYBLUE (-1550 3625);
DISPLAY INVISIBLE (-1550 3625);
FORCEPROP 1 LAST PATH I126
J 0
(-1575 3925);
DISPLAY 0.978723 (-1575 3925);
PAINT WHITE (-1575 3925);
DISPLAY INVISIBLE (-1575 3925);
FORCEPROP 2 LAST CDS_LIB pure_quanta
J 0
(-1525 3775);
DISPLAY INVISIBLE (-1525 3775);
FORCEPROP 1 LAST LOCATION R510
J 0
(-1725 3775);
DISPLAY 0.702128 (-1725 3775);
PAINT YELLOW (-1725 3775);
FORCEPROP 0 LAST $SEC 1
J 0
(-1625 3850);
DISPLAY 0.680851 (-1625 3850);
PAINT MONO (-1625 3850);
DISPLAY INVISIBLE (-1625 3850);
FORCEPROP 0 LAST CDS_SEC 1
J 0
(-1625 3850);
DISPLAY 1.021277 (-1625 3850);
DISPLAY INVISIBLE (-1625 3850);
FORCEPROP 1 LASTPIN (-1625 3775) $PN 1
J 0
(-1613 3787);
DISPLAY 0.808511 (-1613 3787);
PAINT WHITE (-1613 3787);
DISPLAY INVISIBLE (-1613 3787);
FORCEPROP 1 LASTPIN (-1425 3775) $PN 2
J 0
(-1463 3787);
DISPLAY 0.808511 (-1463 3787);
PAINT WHITE (-1463 3787);
DISPLAY INVISIBLE (-1463 3787);
FORCEADD Q_RES..1
(-1525 3725);
FORCEPROP 1 LAST VALUE 33.2
J 0
(-1425 3725);
DISPLAY 0.510638 (-1425 3725);
PAINT SKYBLUE (-1425 3725);
FORCEPROP 1 LAST MATERIAL CHIP
J 0
(-1325 3725);
DISPLAY 0.510638 (-1325 3725);
PAINT SKYBLUE (-1325 3725);
FORCEPROP 1 LAST TOLERANCE 1%
J 0
(-1400 3725);
DISPLAY 0.510638 (-1400 3725);
PAINT SKYBLUE (-1400 3725);
DISPLAY INVISIBLE (-1400 3725);
FORCEPROP 1 LAST PART_NUMBER CS03322FB03
J 0
(-1575 3825);
DISPLAY 0.510638 (-1575 3825);
PAINT WHITE (-1575 3825);
DISPLAY INVISIBLE (-1575 3825);
FORCEPROP 1 LAST PACK_TYPE 0402LF
J 0
(-1275 3575);
DISPLAY 0.510638 (-1275 3575);
PAINT SKYBLUE (-1275 3575);
DISPLAY INVISIBLE (-1275 3575);
FORCEPROP 1 LAST WATTAGE 1/16W
J 2
(-1550 3575);
DISPLAY 0.510638 (-1550 3575);
PAINT SKYBLUE (-1550 3575);
DISPLAY INVISIBLE (-1550 3575);
FORCEPROP 1 LAST PATH I127
J 0
(-1575 3875);
DISPLAY 0.978723 (-1575 3875);
PAINT WHITE (-1575 3875);
DISPLAY INVISIBLE (-1575 3875);
FORCEPROP 2 LAST CDS_LIB pure_quanta
J 0
(-1525 3725);
DISPLAY INVISIBLE (-1525 3725);
FORCEPROP 1 LAST LOCATION R511
J 0
(-1725 3725);
DISPLAY 0.702128 (-1725 3725);
PAINT YELLOW (-1725 3725);
FORCEPROP 0 LAST $SEC 1
J 0
(-1625 3800);
DISPLAY 0.680851 (-1625 3800);
PAINT MONO (-1625 3800);
DISPLAY INVISIBLE (-1625 3800);
FORCEPROP 0 LAST CDS_SEC 1
J 0
(-1625 3800);
DISPLAY 1.021277 (-1625 3800);
DISPLAY INVISIBLE (-1625 3800);
FORCEPROP 1 LASTPIN (-1625 3725) $PN 1
J 0
(-1613 3737);
DISPLAY 0.808511 (-1613 3737);
PAINT WHITE (-1613 3737);
DISPLAY INVISIBLE (-1613 3737);
FORCEPROP 1 LASTPIN (-1425 3725) $PN 2
J 0
(-1463 3737);
DISPLAY 0.808511 (-1463 3737);
PAINT WHITE (-1463 3737);
DISPLAY INVISIBLE (-1463 3737);
FORCEADD Q_RES..1
(-1525 3625);
FORCEPROP 1 LAST VALUE 33.2
J 0
(-1425 3625);
DISPLAY 0.510638 (-1425 3625);
PAINT SKYBLUE (-1425 3625);
FORCEPROP 1 LAST MATERIAL CHIP
J 0
(-1325 3625);
DISPLAY 0.510638 (-1325 3625);
PAINT SKYBLUE (-1325 3625);
FORCEPROP 1 LAST TOLERANCE 1%
J 0
(-1400 3625);
DISPLAY 0.510638 (-1400 3625);
PAINT SKYBLUE (-1400 3625);
DISPLAY INVISIBLE (-1400 3625);
FORCEPROP 1 LAST PART_NUMBER CS03322FB03
J 0
(-1575 3725);
DISPLAY 0.510638 (-1575 3725);
PAINT WHITE (-1575 3725);
DISPLAY INVISIBLE (-1575 3725);
FORCEPROP 1 LAST PACK_TYPE 0402LF
J 0
(-1275 3475);
DISPLAY 0.510638 (-1275 3475);
PAINT SKYBLUE (-1275 3475);
DISPLAY INVISIBLE (-1275 3475);
FORCEPROP 1 LAST WATTAGE 1/16W
J 2
(-1550 3475);
DISPLAY 0.510638 (-1550 3475);
PAINT SKYBLUE (-1550 3475);
DISPLAY INVISIBLE (-1550 3475);
FORCEPROP 1 LAST PATH I128
J 0
(-1575 3775);
DISPLAY 0.978723 (-1575 3775);
PAINT WHITE (-1575 3775);
DISPLAY INVISIBLE (-1575 3775);
FORCEPROP 2 LAST CDS_LIB pure_quanta
J 0
(-1525 3625);
DISPLAY INVISIBLE (-1525 3625);
FORCEPROP 1 LAST LOCATION R513
J 0
(-1725 3625);
DISPLAY 0.702128 (-1725 3625);
PAINT YELLOW (-1725 3625);
FORCEPROP 0 LAST $SEC 1
J 0
(-1625 3700);
DISPLAY 0.680851 (-1625 3700);
PAINT MONO (-1625 3700);
DISPLAY INVISIBLE (-1625 3700);
FORCEPROP 0 LAST CDS_SEC 1
J 0
(-1625 3700);
DISPLAY 1.021277 (-1625 3700);
DISPLAY INVISIBLE (-1625 3700);
FORCEPROP 1 LASTPIN (-1625 3625) $PN 1
J 0
(-1613 3637);
DISPLAY 0.808511 (-1613 3637);
PAINT WHITE (-1613 3637);
DISPLAY INVISIBLE (-1613 3637);
FORCEPROP 1 LASTPIN (-1425 3625) $PN 2
J 0
(-1463 3637);
DISPLAY 0.808511 (-1463 3637);
PAINT WHITE (-1463 3637);
DISPLAY INVISIBLE (-1463 3637);
FORCEADD Q_RES..1
(-1525 3675);
FORCEPROP 1 LAST MATERIAL CHIP
J 0
(-1325 3675);
DISPLAY 0.510638 (-1325 3675);
PAINT SKYBLUE (-1325 3675);
FORCEPROP 1 LAST VALUE 33.2
J 0
(-1425 3675);
DISPLAY 0.510638 (-1425 3675);
PAINT SKYBLUE (-1425 3675);
FORCEPROP 1 LAST TOLERANCE 1%
J 0
(-1400 3675);
DISPLAY 0.510638 (-1400 3675);
PAINT SKYBLUE (-1400 3675);
DISPLAY INVISIBLE (-1400 3675);
FORCEPROP 1 LAST PART_NUMBER CS03322FB03
J 0
(-1575 3775);
DISPLAY 0.510638 (-1575 3775);
PAINT WHITE (-1575 3775);
DISPLAY INVISIBLE (-1575 3775);
FORCEPROP 1 LAST PACK_TYPE 0402LF
J 0
(-1275 3525);
DISPLAY 0.510638 (-1275 3525);
PAINT SKYBLUE (-1275 3525);
DISPLAY INVISIBLE (-1275 3525);
FORCEPROP 1 LAST WATTAGE 1/16W
J 2
(-1550 3525);
DISPLAY 0.510638 (-1550 3525);
PAINT SKYBLUE (-1550 3525);
DISPLAY INVISIBLE (-1550 3525);
FORCEPROP 1 LAST PATH I129
J 0
(-1575 3825);
DISPLAY 0.978723 (-1575 3825);
PAINT WHITE (-1575 3825);
DISPLAY INVISIBLE (-1575 3825);
FORCEPROP 2 LAST CDS_LIB pure_quanta
J 0
(-1525 3675);
DISPLAY INVISIBLE (-1525 3675);
FORCEPROP 1 LAST LOCATION R512
J 0
(-1725 3675);
DISPLAY 0.702128 (-1725 3675);
PAINT YELLOW (-1725 3675);
FORCEPROP 0 LAST $SEC 1
J 0
(-1625 3750);
DISPLAY 0.680851 (-1625 3750);
PAINT MONO (-1625 3750);
DISPLAY INVISIBLE (-1625 3750);
FORCEPROP 0 LAST CDS_SEC 1
J 0
(-1625 3750);
DISPLAY 1.021277 (-1625 3750);
DISPLAY INVISIBLE (-1625 3750);
FORCEPROP 1 LASTPIN (-1625 3675) $PN 1
J 0
(-1613 3687);
DISPLAY 0.808511 (-1613 3687);
PAINT WHITE (-1613 3687);
DISPLAY INVISIBLE (-1613 3687);
FORCEPROP 1 LASTPIN (-1425 3675) $PN 2
J 0
(-1463 3687);
DISPLAY 0.808511 (-1463 3687);
PAINT WHITE (-1463 3687);
DISPLAY INVISIBLE (-1463 3687);
FORCEADD Q_RES..1
(-2425 50);
FORCEPROP 1 LAST VALUE 10K
J 2
(-2175 50);
DISPLAY 0.510638 (-2175 50);
PAINT SKYBLUE (-2175 50);
FORCEPROP 1 LAST MATERIAL EMPTY
J 0
(-2150 50);
DISPLAY 0.510638 (-2150 50);
PAINT RED (-2150 50);
FORCEPROP 2 LAST CDS_LIB pure_quanta
J 0
(-2425 50);
DISPLAY INVISIBLE (-2425 50);
FORCEPROP 1 LAST PATH I131
J 0
(-2475 200);
DISPLAY 0.978723 (-2475 200);
PAINT WHITE (-2475 200);
DISPLAY INVISIBLE (-2475 200);
FORCEPROP 1 LAST PART_NUMBER CS31002FB08
J 0
(-2475 150);
DISPLAY 0.510638 (-2475 150);
PAINT WHITE (-2475 150);
DISPLAY INVISIBLE (-2475 150);
FORCEPROP 1 LAST PACK_TYPE 0402LF
J 0
(-2175 -100);
DISPLAY 0.510638 (-2175 -100);
PAINT SKYBLUE (-2175 -100);
DISPLAY INVISIBLE (-2175 -100);
FORCEPROP 1 LAST TOLERANCE 1%
J 0
(-2425 -50);
DISPLAY 0.510638 (-2425 -50);
PAINT SKYBLUE (-2425 -50);
DISPLAY INVISIBLE (-2425 -50);
FORCEPROP 1 LAST WATTAGE 1/16W
J 2
(-2450 -100);
DISPLAY 0.510638 (-2450 -100);
PAINT SKYBLUE (-2450 -100);
DISPLAY INVISIBLE (-2450 -100);
FORCEPROP 1 LAST LOCATION R834
J 0
(-2725 50);
DISPLAY 0.702128 (-2725 50);
PAINT YELLOW (-2725 50);
FORCEPROP 1 LASTPIN (-2525 50) $PN 1
J 0
(-2513 62);
DISPLAY 0.808511 (-2513 62);
PAINT WHITE (-2513 62);
FORCEPROP 1 LASTPIN (-2325 50) $PN 2
J 0
(-2363 62);
DISPLAY 0.808511 (-2363 62);
PAINT WHITE (-2363 62);
FORCEPROP 0 LAST $SEC 1
J 0
(-2100 100);
DISPLAY 0.680851 (-2100 100);
PAINT MONO (-2100 100);
DISPLAY INVISIBLE (-2100 100);
FORCEPROP 0 LAST CDS_SEC 1
J 0
(-2100 100);
DISPLAY 0.680851 (-2100 100);
DISPLAY INVISIBLE (-2100 100);
FORCEADD CONN8_210HP1080BR1..1
R 2
(2675 3350);
FORCEPROP 1 LAST PART_NUMBER DFHD08MS392
J 2
(2740 3669);
DISPLAY 0.723404 (2740 3669);
PAINT GREEN (2740 3669);
FORCEPROP 2 LAST VALUE CONN8_210-HP1-080BR1
J 2
(2725 3800);
DISPLAY 0.680851 (2725 3800);
FORCEPROP 2 LAST PART_TYPE THLF
J 2
(2725 3850);
DISPLAY 0.680851 (2725 3850);
FORCEPROP 1 LAST MATERIAL IO
J 2
(2740 3580);
DISPLAY 0.723404 (2740 3580);
PAINT GREEN (2740 3580);
FORCEPROP 1 LAST CDS_LMAN_SYM_OUTLINE -50,225,50,-225
J 2
(2675 3350);
DISPLAY 0.468085 (2675 3350);
PAINT GREEN (2675 3350);
DISPLAY INVISIBLE (2675 3350);
FORCEPROP 1 LAST NEEDS_NO_SIZE True
J 2
(2675 3350);
DISPLAY 0.723404 (2675 3350);
PAINT GREEN (2675 3350);
DISPLAY INVISIBLE (2675 3350);
FORCEPROP 1 LAST PATH I132
J 2
(2675 3350);
DISPLAY 0.723404 (2675 3350);
PAINT GREEN (2675 3350);
DISPLAY INVISIBLE (2675 3350);
FORCEPROP 2 LAST CDS_LIB pure_quanta
J 2
(2675 3350);
DISPLAY INVISIBLE (2675 3350);
FORCEPROP 1 LAST LOCATION J7
J 2
(2740 3753);
DISPLAY 0.723404 (2740 3753);
PAINT GREEN (2740 3753);
FORCEPROP 0 LASTPIN (2875 3525) $PN 1
J 0
(2885 3535);
DISPLAY 0.680851 (2885 3535);
PAINT MONO (2885 3535);
FORCEPROP 0 LASTPIN (2875 3475) $PN 2
J 0
(2885 3485);
DISPLAY 0.680851 (2885 3485);
PAINT MONO (2885 3485);
FORCEPROP 0 LASTPIN (2875 3425) $PN 3
J 0
(2885 3435);
DISPLAY 0.680851 (2885 3435);
PAINT MONO (2885 3435);
FORCEPROP 0 LASTPIN (2875 3375) $PN 4
J 0
(2885 3385);
DISPLAY 0.680851 (2885 3385);
PAINT MONO (2885 3385);
FORCEPROP 0 LASTPIN (2875 3325) $PN 5
J 0
(2885 3335);
DISPLAY 0.680851 (2885 3335);
PAINT MONO (2885 3335);
FORCEPROP 0 LASTPIN (2875 3275) $PN 6
J 0
(2885 3285);
DISPLAY 0.680851 (2885 3285);
PAINT MONO (2885 3285);
FORCEPROP 0 LASTPIN (2875 3225) $PN 7
J 0
(2885 3235);
DISPLAY 0.680851 (2885 3235);
PAINT MONO (2885 3235);
FORCEPROP 0 LASTPIN (2875 3175) $PN 8
J 0
(2885 3185);
DISPLAY 0.680851 (2885 3185);
PAINT MONO (2885 3185);
FORCEPROP 0 LAST $SEC 1
J 0
(2725 3900);
DISPLAY 0.680851 (2725 3900);
PAINT MONO (2725 3900);
DISPLAY INVISIBLE (2725 3900);
FORCEPROP 0 LAST CDS_SEC 1
J 0
(2725 3900);
DISPLAY 0.680851 (2725 3900);
DISPLAY INVISIBLE (2725 3900);
FORCEADD Q_RES..1
(-2425 -100);
FORCEPROP 1 LAST VALUE 10K
J 2
(-2175 -100);
DISPLAY 0.510638 (-2175 -100);
PAINT SKYBLUE (-2175 -100);
FORCEPROP 1 LAST MATERIAL EMPTY
J 0
(-2150 -100);
DISPLAY 0.510638 (-2150 -100);
PAINT RED (-2150 -100);
FORCEPROP 1 LAST PART_NUMBER CS31002FB08
J 0
(-2475 0);
DISPLAY 0.510638 (-2475 0);
PAINT WHITE (-2475 0);
DISPLAY INVISIBLE (-2475 0);
FORCEPROP 1 LAST PACK_TYPE 0402LF
J 0
(-2175 -250);
DISPLAY 0.510638 (-2175 -250);
PAINT SKYBLUE (-2175 -250);
DISPLAY INVISIBLE (-2175 -250);
FORCEPROP 1 LAST TOLERANCE 1%
J 0
(-2425 -200);
DISPLAY 0.510638 (-2425 -200);
PAINT SKYBLUE (-2425 -200);
DISPLAY INVISIBLE (-2425 -200);
FORCEPROP 1 LAST WATTAGE 1/16W
J 2
(-2450 -250);
DISPLAY 0.510638 (-2450 -250);
PAINT SKYBLUE (-2450 -250);
DISPLAY INVISIBLE (-2450 -250);
FORCEPROP 1 LAST PATH I140
J 0
(-2475 50);
DISPLAY 0.978723 (-2475 50);
PAINT WHITE (-2475 50);
DISPLAY INVISIBLE (-2475 50);
FORCEPROP 2 LAST CDS_LIB pure_quanta
J 0
(-2425 -100);
DISPLAY INVISIBLE (-2425 -100);
FORCEPROP 1 LAST LOCATION R202
J 0
(-2725 -100);
DISPLAY 0.702128 (-2725 -100);
PAINT YELLOW (-2725 -100);
FORCEPROP 1 LASTPIN (-2525 -100) $PN 1
J 0
(-2513 -88);
DISPLAY 0.787234 (-2513 -88);
PAINT MONO (-2513 -88);
FORCEPROP 1 LASTPIN (-2325 -100) $PN 2
J 0
(-2363 -88);
DISPLAY 0.787234 (-2363 -88);
PAINT MONO (-2363 -88);
FORCEPROP 0 LAST $SEC 1
J 0
(-2725 -50);
DISPLAY 0.680851 (-2725 -50);
PAINT MONO (-2725 -50);
DISPLAY INVISIBLE (-2725 -50);
FORCEPROP 0 LAST CDS_SEC 1
J 0
(-2725 -50);
DISPLAY 0.680851 (-2725 -50);
DISPLAY INVISIBLE (-2725 -50);
FORCEADD Q_RES..1
(-575 4050);
FORCEPROP 1 LAST MATERIAL CHIP
J 0
(-275 4050);
DISPLAY 0.510638 (-275 4050);
PAINT SKYBLUE (-275 4050);
FORCEPROP 1 LAST VALUE 4.7K
J 2
(-325 4050);
DISPLAY 0.510638 (-325 4050);
PAINT SKYBLUE (-325 4050);
FORCEPROP 2 LAST CDS_LIB pure_quanta
J 0
(-575 4050);
DISPLAY INVISIBLE (-575 4050);
FORCEPROP 1 LAST PATH I141
J 0
(-625 4200);
DISPLAY 0.978723 (-625 4200);
PAINT WHITE (-625 4200);
DISPLAY INVISIBLE (-625 4200);
FORCEPROP 1 LAST TOLERANCE 1%
J 0
(-575 3950);
DISPLAY 0.510638 (-575 3950);
PAINT SKYBLUE (-575 3950);
DISPLAY INVISIBLE (-575 3950);
FORCEPROP 1 LAST WATTAGE 1/16W
J 2
(-600 3900);
DISPLAY 0.510638 (-600 3900);
PAINT SKYBLUE (-600 3900);
DISPLAY INVISIBLE (-600 3900);
FORCEPROP 1 LAST PACK_TYPE 0402LF
J 0
(-325 3900);
DISPLAY 0.510638 (-325 3900);
PAINT SKYBLUE (-325 3900);
DISPLAY INVISIBLE (-325 3900);
FORCEPROP 1 LAST PART_NUMBER CS24702FB06
J 0
(-625 4150);
DISPLAY 0.510638 (-625 4150);
PAINT WHITE (-625 4150);
DISPLAY INVISIBLE (-625 4150);
FORCEPROP 1 LAST $LOCATION R285
J 0
(-875 4050);
DISPLAY 0.702128 (-875 4050);
PAINT YELLOW (-875 4050);
FORCEPROP 1 LASTPIN (-675 4050) $PN 1
J 0
(-663 4062);
DISPLAY 0.787234 (-663 4062);
PAINT MONO (-663 4062);
FORCEPROP 1 LASTPIN (-475 4050) $PN 2
J 0
(-513 4062);
DISPLAY 0.787234 (-513 4062);
PAINT MONO (-513 4062);
FORCEPROP 0 LAST CDS_LOCATION R285
J 0
(-875 4100);
DISPLAY 0.680851 (-875 4100);
DISPLAY INVISIBLE (-875 4100);
FORCEPROP 0 LAST $SEC 1
J 0
(-875 4100);
DISPLAY 0.680851 (-875 4100);
PAINT MONO (-875 4100);
DISPLAY INVISIBLE (-875 4100);
FORCEPROP 0 LAST CDS_SEC 1
J 0
(-875 4100);
DISPLAY 0.680851 (-875 4100);
DISPLAY INVISIBLE (-875 4100);
FORCEADD UNIVERSAL_GND..1
R 1
(-125 4050);
FORCEPROP 3 LASTPIN (-175 4050) SIG_NAME GND\g
J 0
(-165 4060);
DISPLAY 0.659574 (-165 4060);
PAINT MONO (-165 4060);
DISPLAY INVISIBLE (-165 4060);
FORCEPROP 2 LAST CDS_LIB logical_power
R 1
J 0
(-125 4050);
DISPLAY INVISIBLE (-125 4050);
FORCEPROP 1 LAST PATH I142
R 1
J 0
(-125 4125);
DISPLAY 0.872340 (-125 4125);
PAINT AQUA (-125 4125);
DISPLAY INVISIBLE (-125 4125);
FORCEPROP 1 LAST HDL_POWER GND
R 1
J 1
(-50 4075);
DISPLAY 0.702128 (-50 4075);
PAINT GREEN (-50 4075);
DISPLAY INVISIBLE (-50 4075);
FORCEADD Q_RES..1
(-2400 -200);
FORCEPROP 1 LAST MATERIAL CHIP
J 0
(-2125 -200);
DISPLAY 0.510638 (-2125 -200);
PAINT SKYBLUE (-2125 -200);
FORCEPROP 1 LAST VALUE 10K
J 2
(-2150 -200);
DISPLAY 0.510638 (-2150 -200);
PAINT SKYBLUE (-2150 -200);
FORCEPROP 1 LAST PART_NUMBER CS31002FB08
J 0
(-2450 -100);
DISPLAY 0.510638 (-2450 -100);
PAINT WHITE (-2450 -100);
DISPLAY INVISIBLE (-2450 -100);
FORCEPROP 1 LAST PACK_TYPE 0402LF
J 0
(-2150 -350);
DISPLAY 0.510638 (-2150 -350);
PAINT SKYBLUE (-2150 -350);
DISPLAY INVISIBLE (-2150 -350);
FORCEPROP 1 LAST WATTAGE 1/16W
J 2
(-2425 -350);
DISPLAY 0.510638 (-2425 -350);
PAINT SKYBLUE (-2425 -350);
DISPLAY INVISIBLE (-2425 -350);
FORCEPROP 1 LAST TOLERANCE 1%
J 0
(-2400 -300);
DISPLAY 0.510638 (-2400 -300);
PAINT SKYBLUE (-2400 -300);
DISPLAY INVISIBLE (-2400 -300);
FORCEPROP 1 LAST PATH I143
J 0
(-2450 -50);
DISPLAY 0.978723 (-2450 -50);
PAINT WHITE (-2450 -50);
DISPLAY INVISIBLE (-2450 -50);
FORCEPROP 2 LAST CDS_LIB pure_quanta
J 0
(-2400 -200);
DISPLAY INVISIBLE (-2400 -200);
FORCEPROP 1 LAST LOCATION R206
J 0
(-2725 -200);
DISPLAY 0.702128 (-2725 -200);
PAINT YELLOW (-2725 -200);
FORCEPROP 1 LASTPIN (-2500 -200) $PN 1
J 0
(-2488 -188);
DISPLAY 0.787234 (-2488 -188);
PAINT MONO (-2488 -188);
FORCEPROP 1 LASTPIN (-2300 -200) $PN 2
J 0
(-2338 -188);
DISPLAY 0.787234 (-2338 -188);
PAINT MONO (-2338 -188);
FORCEPROP 0 LAST $SEC 1
J 0
(-2700 -150);
DISPLAY 0.680851 (-2700 -150);
PAINT MONO (-2700 -150);
DISPLAY INVISIBLE (-2700 -150);
FORCEPROP 0 LAST CDS_SEC 1
J 0
(-2700 -150);
DISPLAY 0.680851 (-2700 -150);
DISPLAY INVISIBLE (-2700 -150);
FORCEADD SCHOTTKY_12..1
R 2
(3850 4325);
FORCEPROP 2 LAST VALUE 1N5819HW
J 2
(3925 4550);
DISPLAY 0.680851 (3925 4550);
FORCEPROP 1 LAST MATERIAL IC
J 2
(3925 4400);
DISPLAY 0.723404 (3925 4400);
PAINT GREEN (3925 4400);
FORCEPROP 2 LAST PART_TYPE SMLF
J 2
(3925 4600);
DISPLAY 0.680851 (3925 4600);
FORCEPROP 1 LAST PART_NUMBER BC005819Z40
J 2
(3925 4450);
DISPLAY 0.723404 (3925 4450);
PAINT GREEN (3925 4450);
FORCEPROP 2 LAST CDS_LIB pure_quanta
J 2
(3850 4325);
DISPLAY INVISIBLE (3850 4325);
FORCEPROP 1 LAST PATH I144
J 2
(3850 4325);
DISPLAY 0.723404 (3850 4325);
PAINT GREEN (3850 4325);
DISPLAY INVISIBLE (3850 4325);
FORCEPROP 1 LAST NEEDS_NO_SIZE TRUE
J 2
(3775 4275);
DISPLAY 0.468085 (3775 4275);
PAINT GREEN (3775 4275);
DISPLAY INVISIBLE (3775 4275);
FORCEPROP 1 LAST CDS_LMAN_SYM_OUTLINE -75,50,75,-50
J 2
(3850 4325);
DISPLAY 0.468085 (3850 4325);
PAINT GREEN (3850 4325);
DISPLAY INVISIBLE (3850 4325);
FORCEPROP 1 LAST $LOCATION D20
J 2
(3925 4500);
DISPLAY 0.723404 (3925 4500);
PAINT GREEN (3925 4500);
FORCEPROP 0 LASTPIN (3975 4325) $PN 1
J 0
(3985 4335);
DISPLAY 0.680851 (3985 4335);
PAINT MONO (3985 4335);
FORCEPROP 0 LASTPIN (3725 4325) $PN 2
J 2
(3715 4335);
DISPLAY 0.680851 (3715 4335);
PAINT MONO (3715 4335);
FORCEPROP 0 LAST CDS_LOCATION D20
J 0
(3925 4650);
DISPLAY 0.680851 (3925 4650);
DISPLAY INVISIBLE (3925 4650);
FORCEPROP 0 LAST $SEC 1
J 0
(3925 4650);
DISPLAY 0.680851 (3925 4650);
PAINT MONO (3925 4650);
DISPLAY INVISIBLE (3925 4650);
FORCEPROP 0 LAST CDS_SEC 1
J 0
(3925 4650);
DISPLAY 0.680851 (3925 4650);
DISPLAY INVISIBLE (3925 4650);
FORCEADD UNIVERSAL_GND..1
(3150 2850);
FORCEPROP 3 LASTPIN (3150 2900) SIG_NAME GND\g
J 0
(3160 2910);
DISPLAY 0.659574 (3160 2910);
PAINT MONO (3160 2910);
DISPLAY INVISIBLE (3160 2910);
FORCEPROP 1 LAST HDL_POWER GND
J 1
(3175 2775);
DISPLAY 0.702128 (3175 2775);
PAINT GREEN (3175 2775);
DISPLAY INVISIBLE (3175 2775);
FORCEPROP 1 LAST PATH I145
J 0
(3225 2850);
DISPLAY 0.872340 (3225 2850);
PAINT AQUA (3225 2850);
DISPLAY INVISIBLE (3225 2850);
FORCEPROP 2 LAST CDS_LIB logical_power
J 0
(3150 2850);
DISPLAY INVISIBLE (3150 2850);
FORCEADD OFFPAGE..2
(5350 3375);
FORCEPROP 2 LAST $XR1 34 
J 0
(5629 3375);
DISPLAY 0.638298 (5629 3375);
PAINT MONO (5629 3375);
FORCEPROP 2 LAST $XR0 48 
J 0
(5539 3375);
DISPLAY 0.638298 (5539 3375);
PAINT MONO (5539 3375);
FORCEPROP 2 LAST CDS_LIB standard
J 0
(5350 3375);
DISPLAY INVISIBLE (5350 3375);
FORCEPROP 1 LAST OFFPAGE TRUE
J 0
(5675 3250);
DISPLAY 0.872340 (5675 3250);
PAINT GREEN (5675 3250);
DISPLAY INVISIBLE (5675 3250);
FORCEPROP 1 LAST COMMENT_BODY TRUE
J 0
(5305 3280);
DISPLAY 0.872340 (5305 3280);
PAINT PEACH (5305 3280);
DISPLAY INVISIBLE (5305 3280);
FORCEPROP 2 LAST PATH I17
J 0
(5400 3450);
DISPLAY 1.021277 (5400 3450);
DISPLAY INVISIBLE (5400 3450);
FORCEADD UNIVERSAL_GND..1
(3575 3625);
FORCEPROP 3 LASTPIN (3575 3675) SIG_NAME GND\g
J 0
(3585 3685);
DISPLAY 0.659574 (3585 3685);
PAINT MONO (3585 3685);
DISPLAY INVISIBLE (3585 3685);
FORCEPROP 2 LAST CDS_LIB logical_power
J 0
(3575 3625);
DISPLAY INVISIBLE (3575 3625);
FORCEPROP 1 LAST PATH I19
J 0
(3650 3625);
DISPLAY 0.872340 (3650 3625);
PAINT AQUA (3650 3625);
DISPLAY INVISIBLE (3650 3625);
FORCEPROP 1 LAST HDL_POWER GND
J 1
(3600 3550);
DISPLAY 0.702128 (3600 3550);
PAINT GREEN (3600 3550);
DISPLAY INVISIBLE (3600 3550);
FORCEADD UNIVERSAL_POWER..1
(4175 4450);
FORCEPROP 3 LASTPIN (4175 4400) SIG_NAME P3V3_AUX\g
J 0
(4185 4410);
DISPLAY 0.659574 (4185 4410);
PAINT MONO (4185 4410);
DISPLAY INVISIBLE (4185 4410);
FORCEPROP 1 LAST HDL_POWER P3V3_AUX
J 1
(4175 4500);
DISPLAY 0.702128 (4175 4500);
PAINT PEACH (4175 4500);
FORCEPROP 1 LAST PATH I20
J 0
(4225 4475);
DISPLAY 0.872340 (4225 4475);
PAINT AQUA (4225 4475);
DISPLAY INVISIBLE (4225 4475);
FORCEPROP 2 LAST CDS_LIB logical_power
J 0
(4175 4450);
DISPLAY INVISIBLE (4175 4450);
FORCEADD Q_CAP..1
(3575 4000);
FORCEPROP 1 LAST MATERIAL X7R
J 0
(3625 3900);
DISPLAY 0.510638 (3625 3900);
PAINT SKYBLUE (3625 3900);
FORCEPROP 1 LAST VOLTAGE 25V
J 0
(3625 4000);
DISPLAY 0.510638 (3625 4000);
PAINT SKYBLUE (3625 4000);
FORCEPROP 1 LAST TOLERANCE 10%
J 0
(3625 3950);
DISPLAY 0.510638 (3625 3950);
PAINT SKYBLUE (3625 3950);
FORCEPROP 1 LAST PACK_TYPE 0402
J 0
(3625 3800);
DISPLAY 0.510638 (3625 3800);
PAINT SKYBLUE (3625 3800);
FORCEPROP 1 LAST PART_NUMBER CH4104K1B00
J 0
(3625 3850);
DISPLAY 0.510638 (3625 3850);
PAINT WHITE (3625 3850);
FORCEPROP 1 LAST VALUE 0.1UF
J 0
(3625 4050);
DISPLAY 0.510638 (3625 4050);
PAINT SKYBLUE (3625 4050);
FORCEPROP 2 LAST CDS_LIB pure_quanta
J 0
(3575 4000);
DISPLAY INVISIBLE (3575 4000);
FORCEPROP 1 LAST PATH I21
J 0
(3625 4150);
DISPLAY 0.978723 (3625 4150);
PAINT WHITE (3625 4150);
DISPLAY INVISIBLE (3625 4150);
FORCEPROP 1 LAST LOCATION C217
J 0
(3625 4100);
DISPLAY 0.702128 (3625 4100);
PAINT YELLOW (3625 4100);
FORCEPROP 0 LAST $SEC 1
J 0
(3625 4150);
DISPLAY 0.680851 (3625 4150);
PAINT MONO (3625 4150);
DISPLAY INVISIBLE (3625 4150);
FORCEPROP 0 LAST CDS_SEC 1
J 0
(3625 4150);
DISPLAY 1.021277 (3625 4150);
DISPLAY INVISIBLE (3625 4150);
FORCEPROP 1 LASTPIN (3575 4100) $PN 1
J 0
(3585 4080);
DISPLAY 0.808511 (3585 4080);
PAINT WHITE (3585 4080);
DISPLAY INVISIBLE (3585 4080);
FORCEPROP 1 LASTPIN (3575 3900) $PN 2
J 0
(3585 3880);
DISPLAY 0.808511 (3585 3880);
PAINT WHITE (3585 3880);
DISPLAY INVISIBLE (3585 3880);
FORCEADD Q_CAP..1
(3275 4000);
FORCEPROP 1 LAST TOLERANCE 20%
J 0
(3325 3950);
DISPLAY 0.510638 (3325 3950);
PAINT SKYBLUE (3325 3950);
FORCEPROP 1 LAST MATERIAL X6S
J 0
(3325 3900);
DISPLAY 0.510638 (3325 3900);
PAINT SKYBLUE (3325 3900);
FORCEPROP 1 LAST PART_NUMBER CH6101MEB01
J 0
(3325 3850);
DISPLAY 0.510638 (3325 3850);
PAINT WHITE (3325 3850);
FORCEPROP 1 LAST PACK_TYPE C0402
J 0
(3325 3800);
DISPLAY 0.510638 (3325 3800);
PAINT SKYBLUE (3325 3800);
FORCEPROP 1 LAST VALUE 10UF
J 0
(3325 4050);
DISPLAY 0.510638 (3325 4050);
PAINT SKYBLUE (3325 4050);
FORCEPROP 1 LAST VOLTAGE 6.3V
J 0
(3325 4000);
DISPLAY 0.510638 (3325 4000);
PAINT SKYBLUE (3325 4000);
FORCEPROP 2 LAST CDS_LIB pure_quanta
J 0
(3275 4000);
DISPLAY INVISIBLE (3275 4000);
FORCEPROP 1 LAST PATH I22
J 0
(3325 4150);
DISPLAY 0.978723 (3325 4150);
PAINT WHITE (3325 4150);
DISPLAY INVISIBLE (3325 4150);
FORCEPROP 1 LAST LOCATION C215
J 0
(3325 4100);
DISPLAY 0.702128 (3325 4100);
PAINT YELLOW (3325 4100);
FORCEPROP 0 LAST $SEC 1
J 0
(3325 4150);
DISPLAY 0.680851 (3325 4150);
PAINT MONO (3325 4150);
DISPLAY INVISIBLE (3325 4150);
FORCEPROP 0 LAST CDS_SEC 1
J 0
(3325 4150);
DISPLAY 1.021277 (3325 4150);
DISPLAY INVISIBLE (3325 4150);
FORCEPROP 1 LASTPIN (3275 4100) $PN 1
J 0
(3285 4080);
DISPLAY 0.808511 (3285 4080);
PAINT WHITE (3285 4080);
DISPLAY INVISIBLE (3285 4080);
FORCEPROP 1 LASTPIN (3275 3900) $PN 2
J 0
(3285 3880);
DISPLAY 0.808511 (3285 3880);
PAINT WHITE (3285 3880);
DISPLAY INVISIBLE (3285 3880);
FORCEADD Q_RES..1
(4250 3375);
FORCEPROP 1 LAST MATERIAL CHIP
J 0
(4425 3375);
DISPLAY 0.510638 (4425 3375);
PAINT SKYBLUE (4425 3375);
FORCEPROP 1 LAST VALUE 33.2
J 0
(4300 3375);
DISPLAY 0.510638 (4300 3375);
PAINT SKYBLUE (4300 3375);
FORCEPROP 1 LAST TOLERANCE 1%
J 0
(4375 3375);
DISPLAY 0.510638 (4375 3375);
PAINT SKYBLUE (4375 3375);
DISPLAY INVISIBLE (4375 3375);
FORCEPROP 1 LAST PART_NUMBER CS03322FB03
J 0
(4200 3475);
DISPLAY 0.510638 (4200 3475);
PAINT WHITE (4200 3475);
DISPLAY INVISIBLE (4200 3475);
FORCEPROP 1 LAST PACK_TYPE 0402LF
J 0
(4500 3225);
DISPLAY 0.510638 (4500 3225);
PAINT SKYBLUE (4500 3225);
DISPLAY INVISIBLE (4500 3225);
FORCEPROP 1 LAST WATTAGE 1/16W
J 2
(4225 3225);
DISPLAY 0.510638 (4225 3225);
PAINT SKYBLUE (4225 3225);
DISPLAY INVISIBLE (4225 3225);
FORCEPROP 1 LAST PATH I23
J 0
(4200 3525);
DISPLAY 0.978723 (4200 3525);
PAINT WHITE (4200 3525);
DISPLAY INVISIBLE (4200 3525);
FORCEPROP 2 LAST CDS_LIB pure_quanta
J 0
(4250 3375);
DISPLAY INVISIBLE (4250 3375);
FORCEPROP 1 LAST LOCATION R518
J 0
(4050 3375);
DISPLAY 0.702128 (4050 3375);
PAINT YELLOW (4050 3375);
FORCEPROP 0 LAST $SEC 1
J 0
(4150 3450);
DISPLAY 0.680851 (4150 3450);
PAINT MONO (4150 3450);
DISPLAY INVISIBLE (4150 3450);
FORCEPROP 0 LAST CDS_SEC 1
J 0
(4150 3450);
DISPLAY 1.021277 (4150 3450);
DISPLAY INVISIBLE (4150 3450);
FORCEPROP 1 LASTPIN (4150 3375) $PN 1
J 0
(4162 3387);
DISPLAY 0.808511 (4162 3387);
PAINT WHITE (4162 3387);
DISPLAY INVISIBLE (4162 3387);
FORCEPROP 1 LASTPIN (4350 3375) $PN 2
J 0
(4312 3387);
DISPLAY 0.808511 (4312 3387);
PAINT WHITE (4312 3387);
DISPLAY INVISIBLE (4312 3387);
FORCEADD OFFPAGE..4
(400 3625);
FORCEPROP 2 LAST $XR0 34 
J 0
(586 3625);
DISPLAY 0.638298 (586 3625);
PAINT MONO (586 3625);
FORCEPROP 2 LAST PATH I41
J 0
(575 3700);
DISPLAY 1.021277 (575 3700);
DISPLAY INVISIBLE (575 3700);
FORCEPROP 1 LAST COMMENT_BODY TRUE
J 0
(375 3525);
DISPLAY 0.872340 (375 3525);
PAINT PEACH (375 3525);
DISPLAY INVISIBLE (375 3525);
FORCEPROP 1 LAST OFFPAGE TRUE
J 0
(725 3500);
DISPLAY 0.872340 (725 3500);
PAINT GREEN (725 3500);
DISPLAY INVISIBLE (725 3500);
FORCEPROP 2 LAST CDS_LIB standard
J 0
(400 3625);
DISPLAY INVISIBLE (400 3625);
FORCEADD OFFPAGE..5
(-2400 3625);
FORCEPROP 2 LAST $XR0 32 
J 0
(-2654 3625);
DISPLAY 0.638298 (-2654 3625);
PAINT MONO (-2654 3625);
FORCEPROP 2 LAST $XR1 15 
J 0
(-2744 3625);
DISPLAY 0.638298 (-2744 3625);
PAINT MONO (-2744 3625);
FORCEPROP 2 LAST PATH I42
J 0
(-2225 3700);
DISPLAY 1.021277 (-2225 3700);
DISPLAY INVISIBLE (-2225 3700);
FORCEPROP 1 LAST COMMENT_BODY TRUE
J 0
(-2300 3550);
DISPLAY 0.872340 (-2300 3550);
PAINT PEACH (-2300 3550);
DISPLAY INVISIBLE (-2300 3550);
FORCEPROP 1 LAST OFFPAGE TRUE
J 0
(-2075 3500);
DISPLAY 0.872340 (-2075 3500);
PAINT GREEN (-2075 3500);
DISPLAY INVISIBLE (-2075 3500);
FORCEPROP 2 LAST CDS_LIB standard
J 0
(-2400 3625);
DISPLAY INVISIBLE (-2400 3625);
FORCEADD OFFPAGE..1
(-2400 3775);
FORCEPROP 2 LAST $XR0 15 
J 0
(-2621 3775);
DISPLAY 0.638298 (-2621 3775);
PAINT MONO (-2621 3775);
FORCEPROP 2 LAST $XR1 32 
J 0
(-2711 3775);
DISPLAY 0.638298 (-2711 3775);
PAINT MONO (-2711 3775);
FORCEPROP 2 LAST PATH I43
J 0
(-2350 3850);
DISPLAY 1.021277 (-2350 3850);
DISPLAY INVISIBLE (-2350 3850);
FORCEPROP 1 LAST COMMENT_BODY TRUE
J 0
(-2275 3675);
DISPLAY 0.872340 (-2275 3675);
PAINT PEACH (-2275 3675);
DISPLAY INVISIBLE (-2275 3675);
FORCEPROP 1 LAST OFFPAGE TRUE
J 0
(-2075 3650);
DISPLAY 0.872340 (-2075 3650);
PAINT GREEN (-2075 3650);
DISPLAY INVISIBLE (-2075 3650);
FORCEPROP 2 LAST CDS_LIB standard
J 0
(-2400 3775);
DISPLAY INVISIBLE (-2400 3775);
FORCEADD OFFPAGE..1
(-2400 3725);
FORCEPROP 2 LAST $XR0 15 
J 0
(-2621 3725);
DISPLAY 0.638298 (-2621 3725);
PAINT MONO (-2621 3725);
FORCEPROP 2 LAST $XR1 32 
J 0
(-2711 3725);
DISPLAY 0.638298 (-2711 3725);
PAINT MONO (-2711 3725);
FORCEPROP 2 LAST PATH I44
J 0
(-2350 3800);
DISPLAY 1.021277 (-2350 3800);
DISPLAY INVISIBLE (-2350 3800);
FORCEPROP 1 LAST COMMENT_BODY TRUE
J 0
(-2275 3625);
DISPLAY 0.872340 (-2275 3625);
PAINT PEACH (-2275 3625);
DISPLAY INVISIBLE (-2275 3625);
FORCEPROP 1 LAST OFFPAGE TRUE
J 0
(-2075 3600);
DISPLAY 0.872340 (-2075 3600);
PAINT GREEN (-2075 3600);
DISPLAY INVISIBLE (-2075 3600);
FORCEPROP 2 LAST CDS_LIB standard
J 0
(-2400 3725);
DISPLAY INVISIBLE (-2400 3725);
FORCEADD OFFPAGE..1
(-2400 3675);
FORCEPROP 2 LAST $XR0 15 
J 0
(-2621 3675);
DISPLAY 0.638298 (-2621 3675);
PAINT MONO (-2621 3675);
FORCEPROP 2 LAST $XR1 32 
J 0
(-2711 3675);
DISPLAY 0.638298 (-2711 3675);
PAINT MONO (-2711 3675);
FORCEPROP 2 LAST PATH I45
J 0
(-2350 3750);
DISPLAY 1.021277 (-2350 3750);
DISPLAY INVISIBLE (-2350 3750);
FORCEPROP 1 LAST COMMENT_BODY TRUE
J 0
(-2275 3575);
DISPLAY 0.872340 (-2275 3575);
PAINT PEACH (-2275 3575);
DISPLAY INVISIBLE (-2275 3575);
FORCEPROP 1 LAST OFFPAGE TRUE
J 0
(-2075 3550);
DISPLAY 0.872340 (-2075 3550);
PAINT GREEN (-2075 3550);
DISPLAY INVISIBLE (-2075 3550);
FORCEPROP 2 LAST CDS_LIB standard
J 0
(-2400 3675);
DISPLAY INVISIBLE (-2400 3675);
FORCEADD OFFPAGE..2
(400 3675);
FORCEPROP 2 LAST $XR0 34 
J 0
(589 3675);
DISPLAY 0.638298 (589 3675);
PAINT MONO (589 3675);
FORCEPROP 2 LAST PATH I49
J 0
(575 3750);
DISPLAY 1.021277 (575 3750);
DISPLAY INVISIBLE (575 3750);
FORCEPROP 1 LAST COMMENT_BODY TRUE
J 0
(355 3580);
DISPLAY 0.872340 (355 3580);
PAINT PEACH (355 3580);
DISPLAY INVISIBLE (355 3580);
FORCEPROP 1 LAST OFFPAGE TRUE
J 0
(725 3550);
DISPLAY 0.872340 (725 3550);
PAINT GREEN (725 3550);
DISPLAY INVISIBLE (725 3550);
FORCEPROP 2 LAST CDS_LIB standard
J 0
(400 3675);
DISPLAY INVISIBLE (400 3675);
FORCEADD OFFPAGE..2
(400 3725);
FORCEPROP 2 LAST $XR0 34 
J 0
(589 3725);
DISPLAY 0.638298 (589 3725);
PAINT MONO (589 3725);
FORCEPROP 2 LAST PATH I50
J 0
(575 3800);
DISPLAY 1.021277 (575 3800);
DISPLAY INVISIBLE (575 3800);
FORCEPROP 1 LAST COMMENT_BODY TRUE
J 0
(355 3630);
DISPLAY 0.872340 (355 3630);
PAINT PEACH (355 3630);
DISPLAY INVISIBLE (355 3630);
FORCEPROP 1 LAST OFFPAGE TRUE
J 0
(725 3600);
DISPLAY 0.872340 (725 3600);
PAINT GREEN (725 3600);
DISPLAY INVISIBLE (725 3600);
FORCEPROP 2 LAST CDS_LIB standard
J 0
(400 3725);
DISPLAY INVISIBLE (400 3725);
FORCEADD OFFPAGE..2
(400 3775);
FORCEPROP 2 LAST $XR0 34 
J 0
(589 3775);
DISPLAY 0.638298 (589 3775);
PAINT MONO (589 3775);
FORCEPROP 2 LAST PATH I51
J 0
(575 3850);
DISPLAY 1.021277 (575 3850);
DISPLAY INVISIBLE (575 3850);
FORCEPROP 1 LAST COMMENT_BODY TRUE
J 0
(355 3680);
DISPLAY 0.872340 (355 3680);
PAINT PEACH (355 3680);
DISPLAY INVISIBLE (355 3680);
FORCEPROP 1 LAST OFFPAGE TRUE
J 0
(725 3650);
DISPLAY 0.872340 (725 3650);
PAINT GREEN (725 3650);
DISPLAY INVISIBLE (725 3650);
FORCEPROP 2 LAST CDS_LIB standard
J 0
(400 3775);
DISPLAY INVISIBLE (400 3775);
FORCEADD OFFPAGE..2
(5350 3175);
FORCEPROP 2 LAST $XR0 32 
J 0
(5539 3175);
DISPLAY 0.638298 (5539 3175);
PAINT MONO (5539 3175);
FORCEPROP 2 LAST PATH I54
J 0
(5400 3250);
DISPLAY 1.021277 (5400 3250);
DISPLAY INVISIBLE (5400 3250);
FORCEPROP 1 LAST COMMENT_BODY TRUE
J 0
(5305 3080);
DISPLAY 0.872340 (5305 3080);
PAINT PEACH (5305 3080);
DISPLAY INVISIBLE (5305 3080);
FORCEPROP 1 LAST OFFPAGE TRUE
J 0
(5675 3050);
DISPLAY 0.872340 (5675 3050);
PAINT GREEN (5675 3050);
DISPLAY INVISIBLE (5675 3050);
FORCEPROP 2 LAST CDS_LIB standard
J 0
(5350 3175);
DISPLAY INVISIBLE (5350 3175);
FORCEADD OFFPAGE..4
(5350 3475);
FORCEPROP 2 LAST $XR0 32 
J 0
(5536 3475);
DISPLAY 0.638298 (5536 3475);
PAINT MONO (5536 3475);
FORCEPROP 2 LAST CDS_LIB standard
J 0
(5350 3475);
DISPLAY INVISIBLE (5350 3475);
FORCEPROP 1 LAST OFFPAGE TRUE
J 0
(5675 3350);
DISPLAY 0.872340 (5675 3350);
PAINT GREEN (5675 3350);
DISPLAY INVISIBLE (5675 3350);
FORCEPROP 1 LAST COMMENT_BODY TRUE
J 0
(5325 3375);
DISPLAY 0.872340 (5325 3375);
PAINT PEACH (5325 3375);
DISPLAY INVISIBLE (5325 3375);
FORCEPROP 2 LAST PATH I55
J 0
(5525 3550);
DISPLAY 1.021277 (5525 3550);
DISPLAY INVISIBLE (5525 3550);
FORCEADD OFFPAGE..2
(5350 3275);
FORCEPROP 2 LAST $XR0 32 
J 0
(5539 3275);
DISPLAY 0.638298 (5539 3275);
PAINT MONO (5539 3275);
FORCEPROP 2 LAST CDS_LIB standard
J 0
(5350 3275);
DISPLAY INVISIBLE (5350 3275);
FORCEPROP 2 LAST PATH I56
J 0
(5525 3350);
DISPLAY 1.021277 (5525 3350);
DISPLAY INVISIBLE (5525 3350);
FORCEPROP 1 LAST COMMENT_BODY TRUE
J 0
(5305 3180);
DISPLAY 0.872340 (5305 3180);
PAINT PEACH (5305 3180);
DISPLAY INVISIBLE (5305 3180);
FORCEPROP 1 LAST OFFPAGE TRUE
J 0
(5675 3150);
DISPLAY 0.872340 (5675 3150);
PAINT GREEN (5675 3150);
DISPLAY INVISIBLE (5675 3150);
FORCEADD OFFPAGE..2
(5350 3425);
FORCEPROP 2 LAST $XR0 32 
J 0
(5539 3425);
DISPLAY 0.638298 (5539 3425);
PAINT MONO (5539 3425);
FORCEPROP 2 LAST CDS_LIB standard
J 0
(5350 3425);
DISPLAY INVISIBLE (5350 3425);
FORCEPROP 1 LAST OFFPAGE TRUE
J 0
(5675 3300);
DISPLAY 0.872340 (5675 3300);
PAINT GREEN (5675 3300);
DISPLAY INVISIBLE (5675 3300);
FORCEPROP 1 LAST COMMENT_BODY TRUE
J 0
(5305 3330);
DISPLAY 0.872340 (5305 3330);
PAINT PEACH (5305 3330);
DISPLAY INVISIBLE (5305 3330);
FORCEPROP 2 LAST PATH I57
J 0
(5525 3500);
DISPLAY 1.021277 (5525 3500);
DISPLAY INVISIBLE (5525 3500);
FORCEADD OFFPAGE..1
(-1900 1825);
FORCEPROP 2 LAST $XR0 15 
J 0
(-2151 1825);
DISPLAY 0.638298 (-2151 1825);
PAINT MONO (-2151 1825);
FORCEPROP 2 LAST PATH I74
J 0
(-2100 1875);
DISPLAY 1.021277 (-2100 1875);
DISPLAY INVISIBLE (-2100 1875);
FORCEPROP 1 LAST COMMENT_BODY TRUE
J 0
(-1775 1725);
DISPLAY 0.872340 (-1775 1725);
PAINT PEACH (-1775 1725);
DISPLAY INVISIBLE (-1775 1725);
FORCEPROP 1 LAST OFFPAGE TRUE
J 0
(-1575 1700);
DISPLAY 0.872340 (-1575 1700);
PAINT GREEN (-1575 1700);
DISPLAY INVISIBLE (-1575 1700);
FORCEPROP 2 LAST CDS_LIB standard
J 0
(-1900 1825);
DISPLAY INVISIBLE (-1900 1825);
FORCEADD OFFPAGE..1
(-1900 1775);
FORCEPROP 2 LAST $XR0 15 
J 0
(-2151 1775);
DISPLAY 0.638298 (-2151 1775);
PAINT MONO (-2151 1775);
FORCEPROP 2 LAST PATH I75
J 0
(-2100 1825);
DISPLAY 1.021277 (-2100 1825);
DISPLAY INVISIBLE (-2100 1825);
FORCEPROP 1 LAST COMMENT_BODY TRUE
J 0
(-1775 1675);
DISPLAY 0.872340 (-1775 1675);
PAINT PEACH (-1775 1675);
DISPLAY INVISIBLE (-1775 1675);
FORCEPROP 1 LAST OFFPAGE TRUE
J 0
(-1575 1650);
DISPLAY 0.872340 (-1575 1650);
PAINT GREEN (-1575 1650);
DISPLAY INVISIBLE (-1575 1650);
FORCEPROP 2 LAST CDS_LIB standard
J 0
(-1900 1775);
DISPLAY INVISIBLE (-1900 1775);
FORCEADD OFFPAGE..1
(-1900 1725);
FORCEPROP 2 LAST $XR0 15 
J 0
(-2151 1725);
DISPLAY 0.638298 (-2151 1725);
PAINT MONO (-2151 1725);
FORCEPROP 2 LAST PATH I76
J 0
(-2100 1775);
DISPLAY 1.021277 (-2100 1775);
DISPLAY INVISIBLE (-2100 1775);
FORCEPROP 1 LAST COMMENT_BODY TRUE
J 0
(-1775 1625);
DISPLAY 0.872340 (-1775 1625);
PAINT PEACH (-1775 1625);
DISPLAY INVISIBLE (-1775 1625);
FORCEPROP 1 LAST OFFPAGE TRUE
J 0
(-1575 1600);
DISPLAY 0.872340 (-1575 1600);
PAINT GREEN (-1575 1600);
DISPLAY INVISIBLE (-1575 1600);
FORCEPROP 2 LAST CDS_LIB standard
J 0
(-1900 1725);
DISPLAY INVISIBLE (-1900 1725);
FORCEADD OFFPAGE..5
(-1900 1675);
FORCEPROP 2 LAST $XR0 15 
J 0
(-2124 1675);
DISPLAY 0.638298 (-2124 1675);
PAINT MONO (-2124 1675);
FORCEPROP 2 LAST PATH I77
J 0
(-2150 1725);
DISPLAY 1.021277 (-2150 1725);
DISPLAY INVISIBLE (-2150 1725);
FORCEPROP 1 LAST COMMENT_BODY TRUE
J 0
(-1800 1600);
DISPLAY 0.872340 (-1800 1600);
PAINT PEACH (-1800 1600);
DISPLAY INVISIBLE (-1800 1600);
FORCEPROP 1 LAST OFFPAGE TRUE
J 0
(-1575 1550);
DISPLAY 0.872340 (-1575 1550);
PAINT GREEN (-1575 1550);
DISPLAY INVISIBLE (-1575 1550);
FORCEPROP 2 LAST CDS_LIB standard
J 0
(-1900 1675);
DISPLAY INVISIBLE (-1900 1675);
FORCEADD Q_RES..1
(-425 1775);
FORCEPROP 1 LAST VALUE 33.2
J 0
(-325 1775);
DISPLAY 0.510638 (-325 1775);
PAINT SKYBLUE (-325 1775);
FORCEPROP 1 LAST MATERIAL CHIP
J 0
(-200 1775);
DISPLAY 0.510638 (-200 1775);
PAINT SKYBLUE (-200 1775);
FORCEPROP 1 LAST TOLERANCE 1%
J 0
(-300 1775);
DISPLAY 0.510638 (-300 1775);
PAINT SKYBLUE (-300 1775);
DISPLAY INVISIBLE (-300 1775);
FORCEPROP 1 LAST PART_NUMBER CS03322FB03
J 0
(-475 1875);
DISPLAY 0.510638 (-475 1875);
PAINT WHITE (-475 1875);
DISPLAY INVISIBLE (-475 1875);
FORCEPROP 1 LAST PACK_TYPE 0402LF
J 0
(-175 1625);
DISPLAY 0.510638 (-175 1625);
PAINT SKYBLUE (-175 1625);
DISPLAY INVISIBLE (-175 1625);
FORCEPROP 1 LAST WATTAGE 1/16W
J 2
(-450 1625);
DISPLAY 0.510638 (-450 1625);
PAINT SKYBLUE (-450 1625);
DISPLAY INVISIBLE (-450 1625);
FORCEPROP 1 LAST PATH I78
J 0
(-475 1925);
DISPLAY 0.978723 (-475 1925);
PAINT WHITE (-475 1925);
DISPLAY INVISIBLE (-475 1925);
FORCEPROP 2 LAST CDS_LIB pure_quanta
J 0
(-425 1775);
DISPLAY INVISIBLE (-425 1775);
FORCEPROP 1 LAST LOCATION R223
J 0
(-650 1775);
DISPLAY 0.702128 (-650 1775);
PAINT YELLOW (-650 1775);
FORCEPROP 1 LASTPIN (-525 1775) $PN 1
J 0
(-513 1787);
DISPLAY 0.808511 (-513 1787);
PAINT WHITE (-513 1787);
FORCEPROP 1 LASTPIN (-325 1775) $PN 2
J 0
(-363 1787);
DISPLAY 0.808511 (-363 1787);
PAINT WHITE (-363 1787);
FORCEPROP 2 LAST $SEC 1
J 0
(-475 1975);
DISPLAY 0.680851 (-475 1975);
PAINT MONO (-475 1975);
DISPLAY INVISIBLE (-475 1975);
FORCEPROP 0 LAST CDS_SEC 1
J 0
(-475 1975);
DISPLAY 0.680851 (-475 1975);
PAINT MONO (-475 1975);
DISPLAY INVISIBLE (-475 1975);
FORCEADD Q_RES..1
(-425 1825);
FORCEPROP 1 LAST VALUE 33.2
J 0
(-325 1825);
DISPLAY 0.510638 (-325 1825);
PAINT SKYBLUE (-325 1825);
FORCEPROP 1 LAST MATERIAL CHIP
J 0
(-200 1825);
DISPLAY 0.510638 (-200 1825);
PAINT SKYBLUE (-200 1825);
FORCEPROP 1 LAST TOLERANCE 1%
J 0
(-300 1825);
DISPLAY 0.510638 (-300 1825);
PAINT SKYBLUE (-300 1825);
DISPLAY INVISIBLE (-300 1825);
FORCEPROP 1 LAST PART_NUMBER CS03322FB03
J 0
(-475 1925);
DISPLAY 0.510638 (-475 1925);
PAINT WHITE (-475 1925);
DISPLAY INVISIBLE (-475 1925);
FORCEPROP 1 LAST PACK_TYPE 0402LF
J 0
(-175 1675);
DISPLAY 0.510638 (-175 1675);
PAINT SKYBLUE (-175 1675);
DISPLAY INVISIBLE (-175 1675);
FORCEPROP 1 LAST WATTAGE 1/16W
J 2
(-450 1675);
DISPLAY 0.510638 (-450 1675);
PAINT SKYBLUE (-450 1675);
DISPLAY INVISIBLE (-450 1675);
FORCEPROP 1 LAST PATH I80
J 0
(-475 1975);
DISPLAY 0.978723 (-475 1975);
PAINT WHITE (-475 1975);
DISPLAY INVISIBLE (-475 1975);
FORCEPROP 2 LAST CDS_LIB pure_quanta
J 0
(-425 1825);
DISPLAY INVISIBLE (-425 1825);
FORCEPROP 1 LAST LOCATION R222
J 0
(-650 1825);
DISPLAY 0.702128 (-650 1825);
PAINT YELLOW (-650 1825);
FORCEPROP 1 LASTPIN (-525 1825) $PN 1
J 0
(-513 1837);
DISPLAY 0.808511 (-513 1837);
PAINT WHITE (-513 1837);
FORCEPROP 1 LASTPIN (-325 1825) $PN 2
J 0
(-363 1837);
DISPLAY 0.808511 (-363 1837);
PAINT WHITE (-363 1837);
FORCEPROP 2 LAST $SEC 1
J 0
(-475 2025);
DISPLAY 0.680851 (-475 2025);
PAINT MONO (-475 2025);
DISPLAY INVISIBLE (-475 2025);
FORCEPROP 0 LAST CDS_SEC 1
J 0
(-475 2025);
DISPLAY 0.680851 (-475 2025);
PAINT MONO (-475 2025);
DISPLAY INVISIBLE (-475 2025);
FORCEADD Q_RES..1
(-425 1875);
FORCEPROP 1 LAST MATERIAL CHIP
J 0
(-200 1875);
DISPLAY 0.510638 (-200 1875);
PAINT SKYBLUE (-200 1875);
FORCEPROP 1 LAST VALUE 33.2
J 0
(-325 1875);
DISPLAY 0.510638 (-325 1875);
PAINT SKYBLUE (-325 1875);
FORCEPROP 1 LAST TOLERANCE 1%
J 0
(-300 1875);
DISPLAY 0.510638 (-300 1875);
PAINT SKYBLUE (-300 1875);
DISPLAY INVISIBLE (-300 1875);
FORCEPROP 1 LAST PART_NUMBER CS03322FB03
J 0
(-475 1975);
DISPLAY 0.510638 (-475 1975);
PAINT WHITE (-475 1975);
DISPLAY INVISIBLE (-475 1975);
FORCEPROP 1 LAST PACK_TYPE 0402LF
J 0
(-175 1725);
DISPLAY 0.510638 (-175 1725);
PAINT SKYBLUE (-175 1725);
DISPLAY INVISIBLE (-175 1725);
FORCEPROP 1 LAST WATTAGE 1/16W
J 2
(-450 1725);
DISPLAY 0.510638 (-450 1725);
PAINT SKYBLUE (-450 1725);
DISPLAY INVISIBLE (-450 1725);
FORCEPROP 1 LAST PATH I81
J 0
(-475 2025);
DISPLAY 0.978723 (-475 2025);
PAINT WHITE (-475 2025);
DISPLAY INVISIBLE (-475 2025);
FORCEPROP 2 LAST CDS_LIB pure_quanta
J 0
(-425 1875);
DISPLAY INVISIBLE (-425 1875);
FORCEPROP 1 LAST LOCATION R221
J 0
(-650 1875);
DISPLAY 0.702128 (-650 1875);
PAINT YELLOW (-650 1875);
FORCEPROP 1 LASTPIN (-525 1875) $PN 1
J 0
(-513 1887);
DISPLAY 0.808511 (-513 1887);
PAINT WHITE (-513 1887);
FORCEPROP 1 LASTPIN (-325 1875) $PN 2
J 0
(-363 1887);
DISPLAY 0.808511 (-363 1887);
PAINT WHITE (-363 1887);
FORCEPROP 2 LAST $SEC 1
J 0
(-475 2075);
DISPLAY 0.680851 (-475 2075);
PAINT MONO (-475 2075);
DISPLAY INVISIBLE (-475 2075);
FORCEPROP 0 LAST CDS_SEC 1
J 0
(-475 2075);
DISPLAY 0.680851 (-475 2075);
PAINT MONO (-475 2075);
DISPLAY INVISIBLE (-475 2075);
FORCEADD OFFPAGE..2
(600 1775);
FORCEPROP 2 LAST $XR0 32 
J 0
(789 1775);
DISPLAY 0.638298 (789 1775);
PAINT MONO (789 1775);
FORCEPROP 2 LAST $XR1 10 
J 0
(879 1775);
DISPLAY 0.638298 (879 1775);
PAINT MONO (879 1775);
FORCEPROP 2 LAST PATH I82
J 0
(900 1825);
DISPLAY 1.021277 (900 1825);
DISPLAY INVISIBLE (900 1825);
FORCEPROP 1 LAST COMMENT_BODY TRUE
J 0
(555 1680);
DISPLAY 0.872340 (555 1680);
PAINT PEACH (555 1680);
DISPLAY INVISIBLE (555 1680);
FORCEPROP 1 LAST OFFPAGE TRUE
J 0
(925 1650);
DISPLAY 0.872340 (925 1650);
PAINT GREEN (925 1650);
DISPLAY INVISIBLE (925 1650);
FORCEPROP 2 LAST CDS_LIB standard
J 0
(600 1775);
DISPLAY INVISIBLE (600 1775);
FORCEADD OFFPAGE..2
(600 1725);
FORCEPROP 2 LAST $XR0 32 
J 0
(789 1725);
DISPLAY 0.638298 (789 1725);
PAINT MONO (789 1725);
FORCEPROP 2 LAST $XR1 10 
J 0
(879 1725);
DISPLAY 0.638298 (879 1725);
PAINT MONO (879 1725);
FORCEPROP 2 LAST PATH I83
J 0
(900 1775);
DISPLAY 1.021277 (900 1775);
DISPLAY INVISIBLE (900 1775);
FORCEPROP 1 LAST COMMENT_BODY TRUE
J 0
(555 1630);
DISPLAY 0.872340 (555 1630);
PAINT PEACH (555 1630);
DISPLAY INVISIBLE (555 1630);
FORCEPROP 1 LAST OFFPAGE TRUE
J 0
(925 1600);
DISPLAY 0.872340 (925 1600);
PAINT GREEN (925 1600);
DISPLAY INVISIBLE (925 1600);
FORCEPROP 2 LAST CDS_LIB standard
J 0
(600 1725);
DISPLAY INVISIBLE (600 1725);
FORCEADD OFFPAGE..2
(600 1825);
FORCEPROP 2 LAST $XR0 32 
J 0
(789 1825);
DISPLAY 0.638298 (789 1825);
PAINT MONO (789 1825);
FORCEPROP 2 LAST $XR1 10 
J 0
(879 1825);
DISPLAY 0.638298 (879 1825);
PAINT MONO (879 1825);
FORCEPROP 2 LAST PATH I84
J 0
(900 1875);
DISPLAY 1.021277 (900 1875);
DISPLAY INVISIBLE (900 1875);
FORCEPROP 1 LAST COMMENT_BODY TRUE
J 0
(555 1730);
DISPLAY 0.872340 (555 1730);
PAINT PEACH (555 1730);
DISPLAY INVISIBLE (555 1730);
FORCEPROP 1 LAST OFFPAGE TRUE
J 0
(925 1700);
DISPLAY 0.872340 (925 1700);
PAINT GREEN (925 1700);
DISPLAY INVISIBLE (925 1700);
FORCEPROP 2 LAST CDS_LIB standard
J 0
(600 1825);
DISPLAY INVISIBLE (600 1825);
FORCEADD OFFPAGE..2
(600 1875);
FORCEPROP 2 LAST $XR0 32 
J 0
(789 1875);
DISPLAY 0.638298 (789 1875);
PAINT MONO (789 1875);
FORCEPROP 2 LAST PATH I85
J 0
(900 1925);
DISPLAY 1.021277 (900 1925);
DISPLAY INVISIBLE (900 1925);
FORCEPROP 1 LAST COMMENT_BODY TRUE
J 0
(555 1780);
DISPLAY 0.872340 (555 1780);
PAINT PEACH (555 1780);
DISPLAY INVISIBLE (555 1780);
FORCEPROP 1 LAST OFFPAGE TRUE
J 0
(925 1750);
DISPLAY 0.872340 (925 1750);
PAINT GREEN (925 1750);
DISPLAY INVISIBLE (925 1750);
FORCEPROP 2 LAST CDS_LIB standard
J 0
(600 1875);
DISPLAY INVISIBLE (600 1875);
FORCEADD OFFPAGE..1
(-1900 1875);
FORCEPROP 2 LAST $XR0 15 
J 0
(-2151 1875);
DISPLAY 0.638298 (-2151 1875);
PAINT MONO (-2151 1875);
FORCEPROP 2 LAST PATH I86
J 0
(-1850 1950);
DISPLAY 1.021277 (-1850 1950);
DISPLAY INVISIBLE (-1850 1950);
FORCEPROP 1 LAST COMMENT_BODY TRUE
J 0
(-1775 1775);
DISPLAY 0.872340 (-1775 1775);
PAINT PEACH (-1775 1775);
DISPLAY INVISIBLE (-1775 1775);
FORCEPROP 1 LAST OFFPAGE TRUE
J 0
(-1575 1750);
DISPLAY 0.872340 (-1575 1750);
PAINT GREEN (-1575 1750);
DISPLAY INVISIBLE (-1575 1750);
FORCEPROP 2 LAST CDS_LIB standard
J 0
(-1900 1875);
DISPLAY INVISIBLE (-1900 1875);
FORCEADD Q_RES..1
(-425 1675);
FORCEPROP 1 LAST PART_NUMBER CS03322FB03
J 0
(-675 1625);
DISPLAY 0.510638 (-675 1625);
PAINT WHITE (-675 1625);
FORCEPROP 1 LAST WATTAGE 1/16W
J 2
(-325 1575);
DISPLAY 0.510638 (-325 1575);
PAINT SKYBLUE (-325 1575);
FORCEPROP 1 LAST TOLERANCE 1%
J 0
(-300 1575);
DISPLAY 0.510638 (-300 1575);
PAINT SKYBLUE (-300 1575);
FORCEPROP 1 LAST PACK_TYPE 0402LF
J 0
(-675 1575);
DISPLAY 0.510638 (-675 1575);
PAINT SKYBLUE (-675 1575);
FORCEPROP 1 LAST MATERIAL CHIP
J 0
(-200 1675);
DISPLAY 0.510638 (-200 1675);
PAINT SKYBLUE (-200 1675);
FORCEPROP 1 LAST VALUE 33.2
J 0
(-325 1675);
DISPLAY 0.510638 (-325 1675);
PAINT SKYBLUE (-325 1675);
FORCEPROP 1 LAST PATH I87
J 0
(-475 1825);
DISPLAY 0.978723 (-475 1825);
PAINT WHITE (-475 1825);
DISPLAY INVISIBLE (-475 1825);
FORCEPROP 2 LAST CDS_LIB pure_quanta
J 0
(-425 1675);
DISPLAY INVISIBLE (-425 1675);
FORCEPROP 1 LAST LOCATION R224
J 0
(-650 1675);
DISPLAY 0.702128 (-650 1675);
PAINT YELLOW (-650 1675);
FORCEPROP 1 LASTPIN (-525 1675) $PN 1
J 0
(-513 1687);
DISPLAY 0.808511 (-513 1687);
PAINT WHITE (-513 1687);
FORCEPROP 1 LASTPIN (-325 1675) $PN 2
J 0
(-363 1687);
DISPLAY 0.808511 (-363 1687);
PAINT WHITE (-363 1687);
FORCEPROP 2 LAST $SEC 1
J 0
(-475 1875);
DISPLAY 0.680851 (-475 1875);
PAINT MONO (-475 1875);
DISPLAY INVISIBLE (-475 1875);
FORCEPROP 0 LAST CDS_SEC 1
J 0
(-475 1875);
DISPLAY 0.680851 (-475 1875);
PAINT MONO (-475 1875);
DISPLAY INVISIBLE (-475 1875);
FORCEADD Q_RES..1
(-425 1725);
FORCEPROP 1 LAST VALUE 33.2
J 0
(-325 1725);
DISPLAY 0.510638 (-325 1725);
PAINT SKYBLUE (-325 1725);
FORCEPROP 1 LAST MATERIAL CHIP
J 0
(-200 1725);
DISPLAY 0.510638 (-200 1725);
PAINT SKYBLUE (-200 1725);
FORCEPROP 1 LAST TOLERANCE 1%
J 0
(-300 1725);
DISPLAY 0.510638 (-300 1725);
PAINT SKYBLUE (-300 1725);
DISPLAY INVISIBLE (-300 1725);
FORCEPROP 1 LAST PART_NUMBER CS03322FB03
J 0
(-475 1825);
DISPLAY 0.510638 (-475 1825);
PAINT WHITE (-475 1825);
DISPLAY INVISIBLE (-475 1825);
FORCEPROP 1 LAST PACK_TYPE 0402LF
J 0
(-175 1575);
DISPLAY 0.510638 (-175 1575);
PAINT SKYBLUE (-175 1575);
DISPLAY INVISIBLE (-175 1575);
FORCEPROP 1 LAST WATTAGE 1/16W
J 2
(-450 1575);
DISPLAY 0.510638 (-450 1575);
PAINT SKYBLUE (-450 1575);
DISPLAY INVISIBLE (-450 1575);
FORCEPROP 1 LAST PATH I88
J 0
(-475 1875);
DISPLAY 0.978723 (-475 1875);
PAINT WHITE (-475 1875);
DISPLAY INVISIBLE (-475 1875);
FORCEPROP 2 LAST CDS_LIB pure_quanta
J 0
(-425 1725);
DISPLAY INVISIBLE (-425 1725);
FORCEPROP 1 LAST LOCATION R639
J 0
(-650 1725);
DISPLAY 0.702128 (-650 1725);
PAINT YELLOW (-650 1725);
FORCEPROP 1 LASTPIN (-525 1725) $PN 1
J 0
(-513 1737);
DISPLAY 0.808511 (-513 1737);
PAINT WHITE (-513 1737);
FORCEPROP 1 LASTPIN (-325 1725) $PN 2
J 0
(-363 1737);
DISPLAY 0.808511 (-363 1737);
PAINT WHITE (-363 1737);
FORCEPROP 2 LAST $SEC 1
J 0
(-475 1925);
DISPLAY 0.680851 (-475 1925);
PAINT MONO (-475 1925);
DISPLAY INVISIBLE (-475 1925);
FORCEPROP 0 LAST CDS_SEC 1
J 0
(-475 1925);
DISPLAY 0.680851 (-475 1925);
PAINT MONO (-475 1925);
DISPLAY INVISIBLE (-475 1925);
FORCEADD OFFPAGE..2
(600 1675);
FORCEPROP 2 LAST $XR0 10 
J 0
(789 1675);
DISPLAY 0.638298 (789 1675);
PAINT MONO (789 1675);
FORCEPROP 2 LAST $XR1 32 
J 0
(879 1675);
DISPLAY 0.638298 (879 1675);
PAINT MONO (879 1675);
FORCEPROP 2 LAST PATH I89
J 0
(900 1725);
DISPLAY 1.021277 (900 1725);
DISPLAY INVISIBLE (900 1725);
FORCEPROP 1 LAST COMMENT_BODY TRUE
J 0
(555 1580);
DISPLAY 0.872340 (555 1580);
PAINT PEACH (555 1580);
DISPLAY INVISIBLE (555 1580);
FORCEPROP 1 LAST OFFPAGE TRUE
J 0
(925 1550);
DISPLAY 0.872340 (925 1550);
PAINT GREEN (925 1550);
DISPLAY INVISIBLE (925 1550);
FORCEPROP 2 LAST CDS_LIB standard
J 0
(600 1675);
DISPLAY INVISIBLE (600 1675);
FORCEADD OFFPAGE..4
(375 3375);
FORCEPROP 2 LAST $XR0 32 
J 0
(561 3375);
DISPLAY 0.638298 (561 3375);
PAINT MONO (561 3375);
FORCEPROP 2 LAST PATH I90
J 0
(575 3425);
DISPLAY 1.021277 (575 3425);
DISPLAY INVISIBLE (575 3425);
FORCEPROP 1 LAST COMMENT_BODY TRUE
J 0
(350 3275);
DISPLAY 0.872340 (350 3275);
PAINT PEACH (350 3275);
DISPLAY INVISIBLE (350 3275);
FORCEPROP 1 LAST OFFPAGE TRUE
J 0
(700 3250);
DISPLAY 0.872340 (700 3250);
PAINT GREEN (700 3250);
DISPLAY INVISIBLE (700 3250);
FORCEPROP 2 LAST CDS_LIB standard
J 0
(375 3375);
DISPLAY INVISIBLE (375 3375);
FORCEADD OFFPAGE..4
(375 3325);
FORCEPROP 2 LAST $XR0 32 
J 0
(561 3325);
DISPLAY 0.638298 (561 3325);
PAINT MONO (561 3325);
FORCEPROP 2 LAST PATH I91
J 0
(575 3375);
DISPLAY 1.021277 (575 3375);
DISPLAY INVISIBLE (575 3375);
FORCEPROP 1 LAST COMMENT_BODY TRUE
J 0
(350 3225);
DISPLAY 0.872340 (350 3225);
PAINT PEACH (350 3225);
DISPLAY INVISIBLE (350 3225);
FORCEPROP 1 LAST OFFPAGE TRUE
J 0
(700 3200);
DISPLAY 0.872340 (700 3200);
PAINT GREEN (700 3200);
DISPLAY INVISIBLE (700 3200);
FORCEPROP 2 LAST CDS_LIB standard
J 0
(375 3325);
DISPLAY INVISIBLE (375 3325);
FORCEADD OFFPAGE..4
(375 3275);
FORCEPROP 2 LAST $XR0 32 
J 0
(561 3275);
DISPLAY 0.638298 (561 3275);
PAINT MONO (561 3275);
FORCEPROP 2 LAST PATH I92
J 0
(575 3325);
DISPLAY 1.021277 (575 3325);
DISPLAY INVISIBLE (575 3325);
FORCEPROP 1 LAST COMMENT_BODY TRUE
J 0
(350 3175);
DISPLAY 0.872340 (350 3175);
PAINT PEACH (350 3175);
DISPLAY INVISIBLE (350 3175);
FORCEPROP 1 LAST OFFPAGE TRUE
J 0
(700 3150);
DISPLAY 0.872340 (700 3150);
PAINT GREEN (700 3150);
DISPLAY INVISIBLE (700 3150);
FORCEPROP 2 LAST CDS_LIB standard
J 0
(375 3275);
DISPLAY INVISIBLE (375 3275);
FORCEADD OFFPAGE..2
(375 3225);
FORCEPROP 2 LAST $XR0 32 
J 0
(564 3225);
DISPLAY 0.638298 (564 3225);
PAINT MONO (564 3225);
FORCEPROP 2 LAST PATH I93
J 0
(575 3275);
DISPLAY 1.021277 (575 3275);
DISPLAY INVISIBLE (575 3275);
FORCEPROP 1 LAST COMMENT_BODY TRUE
J 0
(330 3130);
DISPLAY 0.872340 (330 3130);
PAINT PEACH (330 3130);
DISPLAY INVISIBLE (330 3130);
FORCEPROP 1 LAST OFFPAGE TRUE
J 0
(700 3100);
DISPLAY 0.872340 (700 3100);
PAINT GREEN (700 3100);
DISPLAY INVISIBLE (700 3100);
FORCEPROP 2 LAST CDS_LIB standard
J 0
(375 3225);
DISPLAY INVISIBLE (375 3225);
FORCEADD Q_RES..1
(-700 3375);
FORCEPROP 1 LAST VALUE 33.2
J 0
(-600 3375);
DISPLAY 0.510638 (-600 3375);
PAINT SKYBLUE (-600 3375);
FORCEPROP 1 LAST MATERIAL CHIP
J 0
(-500 3375);
DISPLAY 0.510638 (-500 3375);
PAINT SKYBLUE (-500 3375);
FORCEPROP 1 LAST TOLERANCE 1%
J 0
(-575 3375);
DISPLAY 0.510638 (-575 3375);
PAINT SKYBLUE (-575 3375);
DISPLAY INVISIBLE (-575 3375);
FORCEPROP 1 LAST PART_NUMBER CS03322FB03
J 0
(-750 3475);
DISPLAY 0.510638 (-750 3475);
PAINT WHITE (-750 3475);
DISPLAY INVISIBLE (-750 3475);
FORCEPROP 1 LAST PACK_TYPE 0402LF
J 0
(-450 3225);
DISPLAY 0.510638 (-450 3225);
PAINT SKYBLUE (-450 3225);
DISPLAY INVISIBLE (-450 3225);
FORCEPROP 1 LAST WATTAGE 1/16W
J 2
(-725 3225);
DISPLAY 0.510638 (-725 3225);
PAINT SKYBLUE (-725 3225);
DISPLAY INVISIBLE (-725 3225);
FORCEPROP 1 LAST PATH I94
J 0
(-750 3525);
DISPLAY 0.978723 (-750 3525);
PAINT WHITE (-750 3525);
DISPLAY INVISIBLE (-750 3525);
FORCEPROP 2 LAST CDS_LIB pure_quanta
J 0
(-700 3375);
DISPLAY INVISIBLE (-700 3375);
FORCEPROP 1 LAST LOCATION R514
J 0
(-900 3375);
DISPLAY 0.702128 (-900 3375);
PAINT YELLOW (-900 3375);
FORCEPROP 0 LAST $SEC 1
J 0
(-800 3450);
DISPLAY 0.680851 (-800 3450);
PAINT MONO (-800 3450);
DISPLAY INVISIBLE (-800 3450);
FORCEPROP 0 LAST CDS_SEC 1
J 0
(-800 3450);
DISPLAY 1.021277 (-800 3450);
DISPLAY INVISIBLE (-800 3450);
FORCEPROP 1 LASTPIN (-800 3375) $PN 1
J 0
(-788 3387);
DISPLAY 0.808511 (-788 3387);
PAINT WHITE (-788 3387);
DISPLAY INVISIBLE (-788 3387);
FORCEPROP 1 LASTPIN (-600 3375) $PN 2
J 0
(-638 3387);
DISPLAY 0.808511 (-638 3387);
PAINT WHITE (-638 3387);
DISPLAY INVISIBLE (-638 3387);
FORCEADD Q_RES..1
(-700 3275);
FORCEPROP 1 LAST VALUE 33.2
J 0
(-600 3275);
DISPLAY 0.510638 (-600 3275);
PAINT SKYBLUE (-600 3275);
FORCEPROP 1 LAST MATERIAL CHIP
J 0
(-500 3275);
DISPLAY 0.510638 (-500 3275);
PAINT SKYBLUE (-500 3275);
FORCEPROP 1 LAST TOLERANCE 1%
J 0
(-575 3275);
DISPLAY 0.510638 (-575 3275);
PAINT SKYBLUE (-575 3275);
DISPLAY INVISIBLE (-575 3275);
FORCEPROP 1 LAST PART_NUMBER CS03322FB03
J 0
(-750 3375);
DISPLAY 0.510638 (-750 3375);
PAINT WHITE (-750 3375);
DISPLAY INVISIBLE (-750 3375);
FORCEPROP 1 LAST PACK_TYPE 0402LF
J 0
(-450 3125);
DISPLAY 0.510638 (-450 3125);
PAINT SKYBLUE (-450 3125);
DISPLAY INVISIBLE (-450 3125);
FORCEPROP 1 LAST WATTAGE 1/16W
J 2
(-725 3125);
DISPLAY 0.510638 (-725 3125);
PAINT SKYBLUE (-725 3125);
DISPLAY INVISIBLE (-725 3125);
FORCEPROP 1 LAST PATH I95
J 0
(-750 3425);
DISPLAY 0.978723 (-750 3425);
PAINT WHITE (-750 3425);
DISPLAY INVISIBLE (-750 3425);
FORCEPROP 2 LAST CDS_LIB pure_quanta
J 0
(-700 3275);
DISPLAY INVISIBLE (-700 3275);
FORCEPROP 1 LAST LOCATION R516
J 0
(-900 3275);
DISPLAY 0.702128 (-900 3275);
PAINT YELLOW (-900 3275);
FORCEPROP 0 LAST $SEC 1
J 0
(-800 3350);
DISPLAY 0.680851 (-800 3350);
PAINT MONO (-800 3350);
DISPLAY INVISIBLE (-800 3350);
FORCEPROP 0 LAST CDS_SEC 1
J 0
(-800 3350);
DISPLAY 1.021277 (-800 3350);
DISPLAY INVISIBLE (-800 3350);
FORCEPROP 1 LASTPIN (-800 3275) $PN 1
J 0
(-788 3287);
DISPLAY 0.808511 (-788 3287);
PAINT WHITE (-788 3287);
DISPLAY INVISIBLE (-788 3287);
FORCEPROP 1 LASTPIN (-600 3275) $PN 2
J 0
(-638 3287);
DISPLAY 0.808511 (-638 3287);
PAINT WHITE (-638 3287);
DISPLAY INVISIBLE (-638 3287);
FORCEADD Q_RES..1
(-700 3325);
FORCEPROP 1 LAST VALUE 33.2
J 0
(-600 3325);
DISPLAY 0.510638 (-600 3325);
PAINT SKYBLUE (-600 3325);
FORCEPROP 1 LAST MATERIAL CHIP
J 0
(-500 3325);
DISPLAY 0.510638 (-500 3325);
PAINT SKYBLUE (-500 3325);
FORCEPROP 1 LAST TOLERANCE 1%
J 0
(-575 3325);
DISPLAY 0.510638 (-575 3325);
PAINT SKYBLUE (-575 3325);
DISPLAY INVISIBLE (-575 3325);
FORCEPROP 1 LAST PART_NUMBER CS03322FB03
J 0
(-750 3425);
DISPLAY 0.510638 (-750 3425);
PAINT WHITE (-750 3425);
DISPLAY INVISIBLE (-750 3425);
FORCEPROP 1 LAST PACK_TYPE 0402LF
J 0
(-450 3175);
DISPLAY 0.510638 (-450 3175);
PAINT SKYBLUE (-450 3175);
DISPLAY INVISIBLE (-450 3175);
FORCEPROP 1 LAST WATTAGE 1/16W
J 2
(-725 3175);
DISPLAY 0.510638 (-725 3175);
PAINT SKYBLUE (-725 3175);
DISPLAY INVISIBLE (-725 3175);
FORCEPROP 1 LAST PATH I96
J 0
(-750 3475);
DISPLAY 0.978723 (-750 3475);
PAINT WHITE (-750 3475);
DISPLAY INVISIBLE (-750 3475);
FORCEPROP 2 LAST CDS_LIB pure_quanta
J 0
(-700 3325);
DISPLAY INVISIBLE (-700 3325);
FORCEPROP 1 LAST LOCATION R515
J 0
(-900 3325);
DISPLAY 0.702128 (-900 3325);
PAINT YELLOW (-900 3325);
FORCEPROP 0 LAST $SEC 1
J 0
(-800 3400);
DISPLAY 0.680851 (-800 3400);
PAINT MONO (-800 3400);
DISPLAY INVISIBLE (-800 3400);
FORCEPROP 0 LAST CDS_SEC 1
J 0
(-800 3400);
DISPLAY 1.021277 (-800 3400);
DISPLAY INVISIBLE (-800 3400);
FORCEPROP 1 LASTPIN (-800 3325) $PN 1
J 0
(-788 3337);
DISPLAY 0.808511 (-788 3337);
PAINT WHITE (-788 3337);
DISPLAY INVISIBLE (-788 3337);
FORCEPROP 1 LASTPIN (-600 3325) $PN 2
J 0
(-638 3337);
DISPLAY 0.808511 (-638 3337);
PAINT WHITE (-638 3337);
DISPLAY INVISIBLE (-638 3337);
FORCEADD Q_RES..1
(-700 3225);
FORCEPROP 1 LAST MATERIAL CHIP
J 0
(-500 3225);
DISPLAY 0.510638 (-500 3225);
PAINT SKYBLUE (-500 3225);
FORCEPROP 1 LAST VALUE 33.2
J 0
(-600 3225);
DISPLAY 0.510638 (-600 3225);
PAINT SKYBLUE (-600 3225);
FORCEPROP 1 LAST TOLERANCE 1%
J 0
(-575 3225);
DISPLAY 0.510638 (-575 3225);
PAINT SKYBLUE (-575 3225);
DISPLAY INVISIBLE (-575 3225);
FORCEPROP 1 LAST PART_NUMBER CS03322FB03
J 0
(-750 3325);
DISPLAY 0.510638 (-750 3325);
PAINT WHITE (-750 3325);
DISPLAY INVISIBLE (-750 3325);
FORCEPROP 1 LAST PACK_TYPE 0402LF
J 0
(-450 3075);
DISPLAY 0.510638 (-450 3075);
PAINT SKYBLUE (-450 3075);
DISPLAY INVISIBLE (-450 3075);
FORCEPROP 1 LAST WATTAGE 1/16W
J 2
(-725 3075);
DISPLAY 0.510638 (-725 3075);
PAINT SKYBLUE (-725 3075);
DISPLAY INVISIBLE (-725 3075);
FORCEPROP 1 LAST PATH I97
J 0
(-750 3375);
DISPLAY 0.978723 (-750 3375);
PAINT WHITE (-750 3375);
DISPLAY INVISIBLE (-750 3375);
FORCEPROP 2 LAST CDS_LIB pure_quanta
J 0
(-700 3225);
DISPLAY INVISIBLE (-700 3225);
FORCEPROP 1 LAST LOCATION R517
J 0
(-900 3225);
DISPLAY 0.702128 (-900 3225);
PAINT YELLOW (-900 3225);
FORCEPROP 0 LAST $SEC 1
J 0
(-800 3300);
DISPLAY 0.680851 (-800 3300);
PAINT MONO (-800 3300);
DISPLAY INVISIBLE (-800 3300);
FORCEPROP 0 LAST CDS_SEC 1
J 0
(-800 3300);
DISPLAY 1.021277 (-800 3300);
DISPLAY INVISIBLE (-800 3300);
FORCEPROP 1 LASTPIN (-800 3225) $PN 1
J 0
(-788 3237);
DISPLAY 0.808511 (-788 3237);
PAINT WHITE (-788 3237);
DISPLAY INVISIBLE (-788 3237);
FORCEPROP 1 LASTPIN (-600 3225) $PN 2
J 0
(-638 3237);
DISPLAY 0.808511 (-638 3237);
PAINT WHITE (-638 3237);
DISPLAY INVISIBLE (-638 3237);
FORCEADD OFFPAGE..2
(1000 450);
FORCEPROP 2 LAST $XR0 32 
J 0
(1189 450);
DISPLAY 0.638298 (1189 450);
PAINT MONO (1189 450);
FORCEPROP 2 LAST $XR1 10 
J 0
(1279 450);
DISPLAY 0.638298 (1279 450);
PAINT MONO (1279 450);
FORCEPROP 2 LAST CDS_LIB standard
J 0
(1000 450);
DISPLAY INVISIBLE (1000 450);
FORCEPROP 1 LAST OFFPAGE TRUE
J 0
(1325 325);
DISPLAY 0.872340 (1325 325);
PAINT GREEN (1325 325);
DISPLAY INVISIBLE (1325 325);
FORCEPROP 1 LAST COMMENT_BODY TRUE
J 0
(955 355);
DISPLAY 0.872340 (955 355);
PAINT PEACH (955 355);
DISPLAY INVISIBLE (955 355);
FORCEPROP 2 LAST PATH I98
J 0
(1250 500);
DISPLAY 1.021277 (1250 500);
DISPLAY INVISIBLE (1250 500);
FORCEADD OFFPAGE..2
(1000 250);
FORCEPROP 2 LAST $XR0 32 
J 0
(1189 250);
DISPLAY 0.638298 (1189 250);
PAINT MONO (1189 250);
FORCEPROP 2 LAST $XR1 10 
J 0
(1279 250);
DISPLAY 0.638298 (1279 250);
PAINT MONO (1279 250);
FORCEPROP 2 LAST CDS_LIB standard
J 0
(1000 250);
DISPLAY INVISIBLE (1000 250);
FORCEPROP 1 LAST OFFPAGE TRUE
J 0
(1325 125);
DISPLAY 0.872340 (1325 125);
PAINT GREEN (1325 125);
DISPLAY INVISIBLE (1325 125);
FORCEPROP 1 LAST COMMENT_BODY TRUE
J 0
(955 155);
DISPLAY 0.872340 (955 155);
PAINT PEACH (955 155);
DISPLAY INVISIBLE (955 155);
FORCEPROP 2 LAST PATH I99
J 0
(1300 300);
DISPLAY 1.021277 (1300 300);
DISPLAY INVISIBLE (1300 300);
FORCEADD QUANTA_TITLE_BLOCK_C..1
(5900 -1575);
FORCEPROP 0 LAST CDS_CON_LAST_MODIFIED Fri Aug 25 17:25:43 2023
J 0
(4015 -1560);
DISPLAY INVISIBLE (4015 -1560);
FORCEPROP 2 LAST Q_DEPT 
J 1
(2137 -1526);
DISPLAY 1.957447 (2137 -1526);
PAINT GREEN (2137 -1526);
FORCEPROP 1 LAST CUSTOM_TXT_CDS <CON_LAST_MODIFIED>
J 0
(4015 -1560);
DISPLAY 0.978723 (4015 -1560);
FORCEPROP 2 LAST CUSTOM_TXT_CDS <XR_PAGE_TITLE>
J 0
(-1990 3675);
DISPLAY 0.638298 (-1990 3675);
PAINT PINK (-1990 3675);
DISPLAY INVISIBLE (-1990 3675);
FORCEPROP 1 LAST CUSTOM_TXT_CDS <NAME_2>
J 0
(2725 -1525);
FORCEPROP 1 LAST CUSTOM_TXT_CDS <NAME_1>
J 0
(2725 -1400);
FORCEPROP 1 LAST CUSTOM_TXT_CDS <Q_NUMBER>
J 0
(4497 -1472);
DISPLAY 1.212766 (4497 -1472);
FORCEPROP 1 LAST CUSTOM_TXT_CDS <Q_PROJ>
J 0
(3518 -1473);
DISPLAY 1.212766 (3518 -1473);
FORCEPROP 1 LAST CUSTOM_TXT_CDS <Q_REV>
J 0
(5716 -1472);
DISPLAY 1.212766 (5716 -1472);
FORCEPROP 1 LAST CUSTOM_TXT_CDS <CON_PAGE_NUM> OF <CON_TOTAL_PAGES>
J 0
(5454 -1557);
DISPLAY 0.978723 (5454 -1557);
FORCEPROP 1 LAST Q_TITLE BMC - JTAG
J 0
(-3466 -1549);
DISPLAY 2.446809 (-3466 -1549);
PAINT GREEN (-3466 -1549);
FORCEPROP 2 LAST CDS_XR_PAGE_TITLE CR-32 : @SCM_LIB.SCM(SCH_1):PAGE32
J 0
(-1990 3675);
DISPLAY 0.638298 (-1990 3675);
PAINT PINK (-1990 3675);
DISPLAY INVISIBLE (-1990 3675);
FORCEPROP 1 LAST COMMENT_BODY TRUE
J 0
(5912 -1588);
DISPLAY 0.978723 (5912 -1588);
PAINT PEACH (5912 -1588);
DISPLAY INVISIBLE (5912 -1588);
FORCEPROP 2 LAST PAGE_BORDER TRUE
J 0
(-1990 3675);
DISPLAY 0.638298 (-1990 3675);
PAINT PINK (-1990 3675);
DISPLAY INVISIBLE (-1990 3675);
FORCEPROP 1 LAST CDS_LMAN_SYM_OUTLINE -9475,6775,100,-125
J 0
(5900 -1575);
DISPLAY 0.468085 (5900 -1575);
PAINT GREEN (5900 -1575);
DISPLAY INVISIBLE (5900 -1575);
FORCEPROP 2 LAST CDS_LIB pure_quanta
J 0
(5900 -1575);
DISPLAY INVISIBLE (5900 -1575);
FORCEADD DNS..2
(-2450 -75);
PAINT RED (-2450 -75);
FORCEPROP 1 LAST COMMENT_BODY TRUE
R 1
J 0
(-2375 -300);
DISPLAY 0.872340 (-2375 -300);
PAINT PEACH (-2375 -300);
DISPLAY INVISIBLE (-2375 -300);
FORCEPROP 2 LAST CDS_LIB mstr_misc
J 0
(-2450 -75);
DISPLAY INVISIBLE (-2450 -75);
FORCEADD DNS..2
(-2450 100);
PAINT RED (-2450 100);
FORCEPROP 2 LAST CDS_LIB mstr_misc
J 0
(-2450 100);
DISPLAY INVISIBLE (-2450 100);
FORCEPROP 1 LAST COMMENT_BODY TRUE
R 1
J 0
(-2375 -125);
DISPLAY 0.872340 (-2375 -125);
PAINT PEACH (-2375 -125);
DISPLAY INVISIBLE (-2375 -125);
FORCEADD DNS..2
(-200 -375);
PAINT RED (-200 -375);
FORCEPROP 2 LAST CDS_LIB mstr_misc
J 0
(-200 -375);
DISPLAY INVISIBLE (-200 -375);
FORCEPROP 1 LAST COMMENT_BODY TRUE
R 1
J 0
(-125 -600);
DISPLAY 0.872340 (-125 -600);
PAINT PEACH (-125 -600);
DISPLAY INVISIBLE (-125 -600);
FORCEADD DNS..2
(-200 -200);
PAINT RED (-200 -200);
FORCEPROP 2 LAST CDS_LIB mstr_misc
J 0
(-200 -200);
DISPLAY INVISIBLE (-200 -200);
FORCEPROP 1 LAST COMMENT_BODY TRUE
R 1
J 0
(-125 -425);
DISPLAY 0.872340 (-125 -425);
PAINT PEACH (-125 -425);
DISPLAY INVISIBLE (-125 -425);
FORCEADD DESIGN_NOTE..1
(325 2275);
FORCEPROP 0 LAST L1 TO SCM GF
J 0
(325 2075);
DISPLAY 1.595745 (325 2075);
PAINT WHITE (325 2075);
FORCEPROP 1 LAST COMMENT_BODY TRUE
J 0
(350 2375);
DISPLAY 0.978723 (350 2375);
PAINT PEACH (350 2375);
DISPLAY INVISIBLE (350 2375);
FORCEPROP 2 LAST CDS_LIB logical_power
J 0
(325 2275);
DISPLAY INVISIBLE (325 2275);
FORCEADD DESIGN_NOTE..1
(-2350 2275);
FORCEPROP 0 LAST L1 FROM BMC
J 0
(-2350 2075);
DISPLAY 1.595745 (-2350 2075);
PAINT WHITE (-2350 2075);
FORCEPROP 1 LAST COMMENT_BODY TRUE
J 0
(-2325 2375);
DISPLAY 0.978723 (-2325 2375);
PAINT PEACH (-2325 2375);
DISPLAY INVISIBLE (-2325 2375);
FORCEPROP 2 LAST CDS_LIB logical_power
J 0
(-2350 2275);
DISPLAY INVISIBLE (-2350 2275);
FORCEADD DESIGN_NOTE..1
(-2400 4225);
FORCEPROP 0 LAST L1 FROM BMC
J 0
(-2400 4025);
DISPLAY 1.595745 (-2400 4025);
PAINT WHITE (-2400 4025);
FORCEPROP 1 LAST COMMENT_BODY TRUE
J 0
(-2375 4325);
DISPLAY 0.978723 (-2375 4325);
PAINT PEACH (-2375 4325);
DISPLAY INVISIBLE (-2375 4325);
FORCEPROP 2 LAST CDS_LIB logical_power
J 0
(-2400 4225);
DISPLAY INVISIBLE (-2400 4225);
FORCEADD DESIGN_NOTE..1
(275 4225);
FORCEPROP 0 LAST L1 TO FPGA
J 0
(275 4025);
DISPLAY 1.595745 (275 4025);
PAINT WHITE (275 4025);
FORCEPROP 1 LAST COMMENT_BODY TRUE
J 0
(300 4325);
DISPLAY 0.978723 (300 4325);
PAINT PEACH (300 4325);
DISPLAY INVISIBLE (300 4325);
FORCEPROP 2 LAST CDS_LIB logical_power
J 0
(275 4225);
DISPLAY INVISIBLE (275 4225);
FORCEADD DESIGN_NOTE..1
(250 2875);
FORCEPROP 0 LAST L1 TO DEBUG CONN
J 0
(250 2675);
DISPLAY 1.595745 (250 2675);
PAINT WHITE (250 2675);
FORCEPROP 1 LAST COMMENT_BODY TRUE
J 0
(275 2975);
DISPLAY 0.978723 (275 2975);
PAINT PEACH (275 2975);
DISPLAY INVISIBLE (275 2975);
FORCEPROP 2 LAST CDS_LIB logical_power
J 0
(250 2875);
DISPLAY INVISIBLE (250 2875);
WIRE 16 -1 (-650 675)(-650 450);
WIRE 16 -1 (4175 4400)(4175 4325);
WIRE 16 -1 (-2800 525)(-2800 425);
WIRE 16 -1 (3150 2900)(3150 3225);
WIRE 16 -1 (3575 3675)(3575 3725);
WIRE 16 -1 (-475 4050)(-175 4050);
WIRE 16 -1 (-650 -625)(-650 -350);
WIRE 16 -1 (-2800 -600)(-2800 -200);
WIRE 16 -1 (2875 3225)(3150 3225);
WIRE 16 3135 (5750 4700)(1875 4700);
WIRE 16 3135 (5750 4700)(5750 2625);
WIRE 16 3135 (1875 2625)(1875 4700);
WIRE 16 3135 (1875 2625)(5750 2625);
WIRE 16 -1 (3575 4100)(3575 4325);
WIRE 16 -1 (3575 4325)(3725 4325);
WIRE 16 -1 (3275 4325)(3275 4100);
WIRE 16 -1 (3275 4325)(3575 4325);
WIRE 16 -1 (3275 4325)(3150 4325);
FORCEPROP 2 LAST SIG_NAME J7_P1
J 0
(3190 4335);
DISPLAY 0.851064 (3190 4335);
WIRE 16 -1 (3150 3525)(3150 4325);
WIRE 16 -1 (2875 3525)(3150 3525);
WIRE 16 -1 (3275 3725)(3275 3900);
WIRE 16 -1 (3575 3900)(3575 3725);
WIRE 16 -1 (3575 3725)(3275 3725);
WIRE 16 -1 (2875 3475)(5300 3475);
FORCEPROP 2 LAST SIG_NAME JTAG_SCM_CONN_TDO
J 2
(5215 3485);
DISPLAY 0.808511 (5215 3485);
WIRE 16 -1 (2875 3425)(5300 3425);
FORCEPROP 2 LAST SIG_NAME JTAG_SCM_CONN_TDI
J 2
(5215 3435);
DISPLAY 0.808511 (5215 3435);
WIRE 16 -1 (2875 3375)(4150 3375);
FORCEPROP 2 LAST SIG_NAME JTAG_SCM_PLD_R1_JTAGEN
J 2
(4015 3385);
DISPLAY 0.808511 (4015 3385);
WIRE 16 -1 (2875 3325)(4025 3325);
FORCEPROP 2 LAST SIG_NAME TP_PLD_CONN_P5
J 0
(3190 3335);
DISPLAY 0.851064 (3190 3335);
WIRE 16 -1 (2875 3275)(5300 3275);
FORCEPROP 2 LAST SIG_NAME JTAG_SCM_CONN_TMS
J 2
(5215 3285);
DISPLAY 0.808511 (5215 3285);
WIRE 16 -1 (2875 3175)(5300 3175);
FORCEPROP 2 LAST SIG_NAME JTAG_SCM_CONN_TCK
J 2
(5215 3185);
DISPLAY 0.808511 (5215 3185);
WIRE 16 -1 (-600 3225)(325 3225);
FORCEPROP 2 LAST SIG_NAME JTAG_SCM_CONN_TDO
J 0
(-360 3235);
DISPLAY 0.808511 (-360 3235);
WIRE 16 3135 (1450 950)(-3050 950);
WIRE 16 3135 (1450 950)(1450 -700);
WIRE 16 3135 (-3050 -700)(-3050 950);
WIRE 16 3135 (-3050 -700)(1450 -700);
WIRE 16 -1 (550 1725)(-325 1725);
FORCEPROP 2 LAST SIG_NAME JTAG_MB_TDI
J 0
(-85 1735);
DISPLAY 0.808511 (-85 1735);
WIRE 16 -1 (550 1775)(-325 1775);
FORCEPROP 2 LAST SIG_NAME JTAG_MB_TMS
J 0
(-85 1785);
DISPLAY 0.808511 (-85 1785);
WIRE 16 -1 (550 1675)(-325 1675);
FORCEPROP 2 LAST SIG_NAME JTAG_MB_TDO
J 0
(-85 1685);
DISPLAY 0.808511 (-85 1685);
WIRE 16 -1 (-100 450)(950 450);
FORCEPROP 2 LAST SIG_NAME JTAG_MB_TDI
J 2
(875 460);
DISPLAY 0.808511 (875 460);
WIRE 16 -1 (-100 250)(950 250);
FORCEPROP 2 LAST SIG_NAME JTAG_MB_TMS
J 2
(875 260);
DISPLAY 0.808511 (875 260);
WIRE 16 -1 (-100 125)(950 125);
FORCEPROP 2 LAST SIG_NAME JTAG_MB_TDO
J 2
(875 135);
DISPLAY 0.808511 (875 135);
WIRE 16 -1 (-100 -225)(950 -225);
FORCEPROP 2 LAST SIG_NAME JTAG_MB_TRST_N
J 2
(875 -215);
DISPLAY 0.808511 (875 -215);
WIRE 16 -1 (-100 -350)(950 -350);
FORCEPROP 2 LAST SIG_NAME JTAG_MB_TCK
J 2
(875 -340);
DISPLAY 0.808511 (875 -340);
WIRE 16 -1 (-650 -350)(-300 -350);
WIRE 16 -1 (-650 -350)(-650 -225);
WIRE 16 -1 (-300 -225)(-650 -225);
WIRE 16 -1 (-2500 -200)(-2800 -200);
WIRE 16 -1 (-2800 -100)(-2800 -200);
WIRE 16 -1 (-2525 -100)(-2800 -100);
WIRE 16 -1 (-2300 -200)(-1375 -200);
FORCEPROP 2 LAST SIG_NAME JTAG_SCM_NTRST
J 2
(-1400 -190);
DISPLAY 0.808511 (-1400 -190);
WIRE 16 -1 (550 1825)(-325 1825);
FORCEPROP 2 LAST SIG_NAME JTAG_MB_TCK
J 0
(-85 1835);
DISPLAY 0.808511 (-85 1835);
WIRE 16 -1 (550 1875)(-325 1875);
FORCEPROP 2 LAST SIG_NAME JTAG_MB_TRST_N
J 0
(-85 1885);
DISPLAY 0.808511 (-85 1885);
WIRE 16 -1 (4350 3375)(5300 3375);
FORCEPROP 2 LAST SIG_NAME JTAG_SCM_PLD_JTAGEN
J 2
(5290 3385);
DISPLAY 0.808511 (5290 3385);
WIRE 16 -1 (-675 4050)(-750 4050);
WIRE 16 -1 (-750 4050)(-750 3775);
WIRE 16 -1 (-750 3775)(350 3775);
FORCEPROP 2 LAST SIG_NAME JTAG_SCM_PLD_TCK
J 0
(-335 3785);
DISPLAY 0.808511 (-335 3785);
WIRE 16 -1 (-950 3775)(-750 3775);
WIRE 16 -1 (-1425 3775)(-950 3775);
WIRE 16 -1 (-950 3775)(-950 3375);
WIRE 16 -1 (-800 3375)(-950 3375);
WIRE 16 -1 (-2350 3775)(-1625 3775);
FORCEPROP 2 LAST SIG_NAME JTAG_SCM_TCK
J 0
(-2260 3785);
DISPLAY 0.808511 (-2260 3785);
WIRE 16 -1 (-2350 3725)(-1625 3725);
FORCEPROP 2 LAST SIG_NAME JTAG_SCM_TMS
J 0
(-2260 3735);
DISPLAY 0.808511 (-2260 3735);
WIRE 16 -1 (-2350 3675)(-1625 3675);
FORCEPROP 2 LAST SIG_NAME JTAG_SCM_TDI
J 0
(-2260 3685);
DISPLAY 0.808511 (-2260 3685);
WIRE 16 -1 (-650 450)(-300 450);
WIRE 16 -1 (-650 450)(-650 250);
WIRE 16 -1 (-650 250)(-300 250);
WIRE 16 -1 (-650 125)(-650 250);
WIRE 16 -1 (-650 125)(-300 125);
WIRE 16 -1 (-2325 50)(-2000 50);
WIRE 16 -1 (-2000 -100)(-1375 -100);
FORCEPROP 2 LAST SIG_NAME JTAG_SCM_TCK
J 2
(-1400 -90);
DISPLAY 0.808511 (-1400 -90);
WIRE 16 -1 (-2000 50)(-2000 -100);
WIRE 16 -1 (-2325 -100)(-2000 -100);
WIRE 16 -1 (-1850 1675)(-525 1675);
FORCEPROP 2 LAST SIG_NAME JTAG_1_BMC_TDO_R
J 0
(-1810 1685);
DISPLAY 0.808511 (-1810 1685);
WIRE 16 -1 (-1850 1725)(-525 1725);
FORCEPROP 2 LAST SIG_NAME JTAG_1_BMC_TDI_R
J 0
(-1810 1735);
DISPLAY 0.808511 (-1810 1735);
WIRE 16 -1 (-1850 1775)(-525 1775);
FORCEPROP 2 LAST SIG_NAME JTAG_1_BMC_TMS_R
J 0
(-1810 1785);
DISPLAY 0.808511 (-1810 1785);
WIRE 16 -1 (-1850 1825)(-525 1825);
FORCEPROP 2 LAST SIG_NAME JTAG_1_BMC_TCK_R
J 0
(-1810 1835);
DISPLAY 0.808511 (-1810 1835);
WIRE 16 -1 (-1850 1875)(-525 1875);
FORCEPROP 2 LAST SIG_NAME JTAG_1_BMC_TRST_R
J 0
(-1810 1885);
DISPLAY 0.808511 (-1810 1885);
WIRE 16 -1 (-800 3275)(-1100 3275);
WIRE 16 -1 (-1100 3275)(-1100 3675);
WIRE 16 -1 (350 3675)(-1100 3675);
FORCEPROP 2 LAST SIG_NAME JTAG_SCM_PLD_TDI
J 0
(-335 3685);
DISPLAY 0.808511 (-335 3685);
WIRE 16 -1 (-1425 3675)(-1100 3675);
WIRE 16 -1 (-800 3325)(-1025 3325);
WIRE 16 -1 (-1025 3325)(-1025 3725);
WIRE 16 -1 (350 3725)(-1025 3725);
FORCEPROP 2 LAST SIG_NAME JTAG_SCM_PLD_TMS
J 0
(-335 3735);
DISPLAY 0.808511 (-335 3735);
WIRE 16 -1 (-1425 3725)(-1025 3725);
WIRE 16 -1 (-800 3225)(-1175 3225);
WIRE 16 -1 (-1175 3225)(-1175 3625);
WIRE 16 -1 (-1175 3625)(-1425 3625);
WIRE 16 -1 (350 3625)(-1175 3625);
FORCEPROP 2 LAST SIG_NAME JTAG_SCM_PLD_TDO
J 0
(-335 3635);
DISPLAY 0.808511 (-335 3635);
WIRE 16 -1 (-600 3275)(325 3275);
FORCEPROP 2 LAST SIG_NAME JTAG_SCM_CONN_TDI
J 0
(-360 3285);
DISPLAY 0.808511 (-360 3285);
WIRE 16 -1 (-1625 3625)(-2350 3625);
FORCEPROP 2 LAST SIG_NAME JTAG_SCM_TDO
J 0
(-2260 3625);
DISPLAY 0.808511 (-2260 3625);
WIRE 16 -1 (-2800 50)(-2525 50);
WIRE 16 -1 (-2800 275)(-2800 50);
WIRE 16 -1 (-2800 275)(-2525 275);
WIRE 16 -1 (-2800 350)(-2800 275);
WIRE 16 -1 (-2525 350)(-2800 350);
WIRE 16 -1 (-2800 425)(-2800 350);
WIRE 16 -1 (-2800 425)(-2525 425);
WIRE 16 -1 (-2325 350)(-1375 350);
FORCEPROP 2 LAST SIG_NAME JTAG_SCM_TDI
J 2
(-1400 360);
DISPLAY 0.808511 (-1400 360);
WIRE 16 -1 (-2325 425)(-1375 425);
FORCEPROP 2 LAST SIG_NAME JTAG_SCM_TMS
J 2
(-1400 435);
DISPLAY 0.808511 (-1400 435);
WIRE 16 -1 (-1375 275)(-2325 275);
FORCEPROP 2 LAST SIG_NAME JTAG_SCM_TDO
J 2
(-1400 275);
DISPLAY 0.808511 (-1400 275);
WIRE 16 -1 (-600 3325)(325 3325);
FORCEPROP 2 LAST SIG_NAME JTAG_SCM_CONN_TMS
J 0
(-360 3335);
DISPLAY 0.808511 (-360 3335);
WIRE 16 -1 (-600 3375)(325 3375);
FORCEPROP 2 LAST SIG_NAME JTAG_SCM_CONN_TCK
J 0
(-360 3385);
DISPLAY 0.808511 (-360 3385);
WIRE 16 -1 (3975 4325)(4175 4325);
DOT 1 (3575 3725);
DOT 1 (-650 450);
DOT 1 (-950 3775);
DOT 1 (-1100 3675);
DOT 1 (-1025 3725);
DOT 1 (-650 -350);
DOT 1 (-2800 425);
DOT 1 (-2800 350);
DOT 1 (-2800 275);
DOT 1 (-2000 -100);
DOT 1 (-2800 -200);
DOT 1 (-750 3775);
DOT 1 (-1175 3625);
DOT 1 (-650 250);
DOT 1 (3275 4325);
DOT 1 (3575 4325);
FORCENOTE
FOR FPGA PROGRAMMING
(1975 4550) 0;
DISPLAY LEFT (1975 4550);
DISPLAY 1.021277 (1975 4550);
FORCENOTE
JTAG MASTER PU/PD RESISTOR
(-2625 775) 0;
DISPLAY LEFT (-2625 775);
DISPLAY 1.021277 (-2625 775);
PAINT WHITE (-2625 775);
QUIT
